FILE_TYPE = MACRO_DRAWING;
SET COLOR_WIRE YELLOW;
SET COLOR_PROP ORANGE;
SET COLOR_DOT WHITE;
SET COLOR_ARC YELLOW;
SET COLOR_BODY GREEN;
SET COLOR_NOTE PURPLE;
SET PROP_DISPLAY VALUE;
SET PAGE_NUMBER P62;
FORCEADD TAP..1
R 2
(-1550 3200);
FORCEPROP 3 LASTPIN (-1500 3200) SIG_NAME P5E_CPU1_PE4_RX_DN<3>
J 0
(-1490 3210);
DISPLAY 0.659574 (-1490 3210);
PAINT MONO (-1490 3210);
DISPLAY INVISIBLE (-1490 3210);
FORCEPROP 1 LASTPIN (-1500 3200) BN 3
J 2
(-1488 3208);
DISPLAY 0.680851 (-1488 3208);
PAINT GREEN (-1488 3208);
FORCEPROP 2 LAST CDS_LIB standard
J 0
(-1550 3200);
DISPLAY INVISIBLE (-1550 3200);
FORCEPROP 1 LAST BODY_TYPE PLUMBING
J 2
(-1550 3250);
DISPLAY 0.872340 (-1550 3250);
PAINT GREEN (-1550 3250);
DISPLAY INVISIBLE (-1550 3250);
FORCEPROP 1 LAST HDL_TAP TRUE
J 2
(-1875 3075);
DISPLAY 0.872340 (-1875 3075);
DISPLAY INVISIBLE (-1875 3075);
FORCEPROP 1 LAST PATH I100
J 2
(-1548 3200);
DISPLAY 0.872340 (-1548 3200);
PAINT GREEN (-1548 3200);
DISPLAY INVISIBLE (-1548 3200);
FORCEADD TAP..1
R 2
(-1550 3150);
FORCEPROP 3 LASTPIN (-1500 3150) SIG_NAME P5E_CPU1_PE4_RX_DN<2>
J 0
(-1490 3160);
DISPLAY 0.659574 (-1490 3160);
PAINT MONO (-1490 3160);
DISPLAY INVISIBLE (-1490 3160);
FORCEPROP 1 LASTPIN (-1500 3150) BN 2
J 2
(-1488 3158);
DISPLAY 0.680851 (-1488 3158);
PAINT GREEN (-1488 3158);
FORCEPROP 2 LAST CDS_LIB standard
J 0
(-1550 3150);
DISPLAY INVISIBLE (-1550 3150);
FORCEPROP 1 LAST BODY_TYPE PLUMBING
J 2
(-1550 3200);
DISPLAY 0.872340 (-1550 3200);
PAINT GREEN (-1550 3200);
DISPLAY INVISIBLE (-1550 3200);
FORCEPROP 1 LAST HDL_TAP TRUE
J 2
(-1875 3025);
DISPLAY 0.872340 (-1875 3025);
DISPLAY INVISIBLE (-1875 3025);
FORCEPROP 1 LAST PATH I101
J 2
(-1548 3150);
DISPLAY 0.872340 (-1548 3150);
PAINT GREEN (-1548 3150);
DISPLAY INVISIBLE (-1548 3150);
FORCEADD TAP..1
R 2
(-1550 3300);
FORCEPROP 3 LASTPIN (-1500 3300) SIG_NAME P5E_CPU1_PE4_RX_DN<5>
J 0
(-1490 3310);
DISPLAY 0.659574 (-1490 3310);
PAINT MONO (-1490 3310);
DISPLAY INVISIBLE (-1490 3310);
FORCEPROP 1 LASTPIN (-1500 3300) BN 5
J 2
(-1488 3308);
DISPLAY 0.680851 (-1488 3308);
PAINT GREEN (-1488 3308);
FORCEPROP 2 LAST CDS_LIB standard
J 0
(-1550 3300);
DISPLAY INVISIBLE (-1550 3300);
FORCEPROP 1 LAST BODY_TYPE PLUMBING
J 2
(-1550 3350);
DISPLAY 0.872340 (-1550 3350);
PAINT GREEN (-1550 3350);
DISPLAY INVISIBLE (-1550 3350);
FORCEPROP 1 LAST HDL_TAP TRUE
J 2
(-1875 3175);
DISPLAY 0.872340 (-1875 3175);
DISPLAY INVISIBLE (-1875 3175);
FORCEPROP 1 LAST PATH I102
J 2
(-1548 3300);
DISPLAY 0.872340 (-1548 3300);
PAINT GREEN (-1548 3300);
DISPLAY INVISIBLE (-1548 3300);
FORCEADD TAP..1
R 2
(-1550 3250);
FORCEPROP 3 LASTPIN (-1500 3250) SIG_NAME P5E_CPU1_PE4_RX_DN<4>
J 0
(-1490 3260);
DISPLAY 0.659574 (-1490 3260);
PAINT MONO (-1490 3260);
DISPLAY INVISIBLE (-1490 3260);
FORCEPROP 1 LASTPIN (-1500 3250) BN 4
J 2
(-1488 3258);
DISPLAY 0.680851 (-1488 3258);
PAINT GREEN (-1488 3258);
FORCEPROP 2 LAST CDS_LIB standard
J 0
(-1550 3250);
DISPLAY INVISIBLE (-1550 3250);
FORCEPROP 1 LAST BODY_TYPE PLUMBING
J 2
(-1550 3300);
DISPLAY 0.872340 (-1550 3300);
PAINT GREEN (-1550 3300);
DISPLAY INVISIBLE (-1550 3300);
FORCEPROP 1 LAST HDL_TAP TRUE
J 2
(-1875 3125);
DISPLAY 0.872340 (-1875 3125);
DISPLAY INVISIBLE (-1875 3125);
FORCEPROP 1 LAST PATH I103
J 2
(-1548 3250);
DISPLAY 0.872340 (-1548 3250);
PAINT GREEN (-1548 3250);
DISPLAY INVISIBLE (-1548 3250);
FORCEADD TAP..1
R 2
(-1550 3350);
FORCEPROP 3 LASTPIN (-1500 3350) SIG_NAME P5E_CPU1_PE4_RX_DN<6>
J 0
(-1490 3360);
DISPLAY 0.659574 (-1490 3360);
PAINT MONO (-1490 3360);
DISPLAY INVISIBLE (-1490 3360);
FORCEPROP 1 LASTPIN (-1500 3350) BN 6
J 2
(-1488 3358);
DISPLAY 0.680851 (-1488 3358);
PAINT GREEN (-1488 3358);
FORCEPROP 2 LAST CDS_LIB standard
J 0
(-1550 3350);
DISPLAY INVISIBLE (-1550 3350);
FORCEPROP 1 LAST BODY_TYPE PLUMBING
J 2
(-1550 3400);
DISPLAY 0.872340 (-1550 3400);
PAINT GREEN (-1550 3400);
DISPLAY INVISIBLE (-1550 3400);
FORCEPROP 1 LAST HDL_TAP TRUE
J 2
(-1875 3225);
DISPLAY 0.872340 (-1875 3225);
DISPLAY INVISIBLE (-1875 3225);
FORCEPROP 1 LAST PATH I104
J 2
(-1548 3350);
DISPLAY 0.872340 (-1548 3350);
PAINT GREEN (-1548 3350);
DISPLAY INVISIBLE (-1548 3350);
FORCEADD TAP..1
R 2
(-1550 3450);
FORCEPROP 3 LASTPIN (-1500 3450) SIG_NAME P5E_CPU1_PE4_RX_DN<8>
J 0
(-1490 3460);
DISPLAY 0.659574 (-1490 3460);
PAINT MONO (-1490 3460);
DISPLAY INVISIBLE (-1490 3460);
FORCEPROP 1 LASTPIN (-1500 3450) BN 8
J 2
(-1488 3458);
DISPLAY 0.680851 (-1488 3458);
PAINT GREEN (-1488 3458);
FORCEPROP 2 LAST CDS_LIB standard
J 0
(-1550 3450);
DISPLAY INVISIBLE (-1550 3450);
FORCEPROP 1 LAST BODY_TYPE PLUMBING
J 2
(-1550 3500);
DISPLAY 0.872340 (-1550 3500);
PAINT GREEN (-1550 3500);
DISPLAY INVISIBLE (-1550 3500);
FORCEPROP 1 LAST HDL_TAP TRUE
J 2
(-1875 3325);
DISPLAY 0.872340 (-1875 3325);
DISPLAY INVISIBLE (-1875 3325);
FORCEPROP 1 LAST PATH I105
J 2
(-1548 3450);
DISPLAY 0.872340 (-1548 3450);
PAINT GREEN (-1548 3450);
DISPLAY INVISIBLE (-1548 3450);
FORCEADD TAP..1
R 2
(-1550 3400);
FORCEPROP 3 LASTPIN (-1500 3400) SIG_NAME P5E_CPU1_PE4_RX_DN<7>
J 0
(-1490 3410);
DISPLAY 0.659574 (-1490 3410);
PAINT MONO (-1490 3410);
DISPLAY INVISIBLE (-1490 3410);
FORCEPROP 1 LASTPIN (-1500 3400) BN 7
J 2
(-1488 3408);
DISPLAY 0.680851 (-1488 3408);
PAINT GREEN (-1488 3408);
FORCEPROP 2 LAST CDS_LIB standard
J 0
(-1550 3400);
DISPLAY INVISIBLE (-1550 3400);
FORCEPROP 1 LAST BODY_TYPE PLUMBING
J 2
(-1550 3450);
DISPLAY 0.872340 (-1550 3450);
PAINT GREEN (-1550 3450);
DISPLAY INVISIBLE (-1550 3450);
FORCEPROP 1 LAST HDL_TAP TRUE
J 2
(-1875 3275);
DISPLAY 0.872340 (-1875 3275);
DISPLAY INVISIBLE (-1875 3275);
FORCEPROP 1 LAST PATH I106
J 2
(-1548 3400);
DISPLAY 0.872340 (-1548 3400);
PAINT GREEN (-1548 3400);
DISPLAY INVISIBLE (-1548 3400);
FORCEADD TAP..1
R 2
(-1550 3550);
FORCEPROP 3 LASTPIN (-1500 3550) SIG_NAME P5E_CPU1_PE4_RX_DN<10>
J 0
(-1490 3560);
DISPLAY 0.659574 (-1490 3560);
PAINT MONO (-1490 3560);
DISPLAY INVISIBLE (-1490 3560);
FORCEPROP 1 LASTPIN (-1500 3550) BN 10
J 2
(-1488 3558);
DISPLAY 0.680851 (-1488 3558);
PAINT GREEN (-1488 3558);
FORCEPROP 2 LAST CDS_LIB standard
J 0
(-1550 3550);
DISPLAY INVISIBLE (-1550 3550);
FORCEPROP 1 LAST BODY_TYPE PLUMBING
J 2
(-1550 3600);
DISPLAY 0.872340 (-1550 3600);
PAINT GREEN (-1550 3600);
DISPLAY INVISIBLE (-1550 3600);
FORCEPROP 1 LAST HDL_TAP TRUE
J 2
(-1875 3425);
DISPLAY 0.872340 (-1875 3425);
DISPLAY INVISIBLE (-1875 3425);
FORCEPROP 1 LAST PATH I107
J 2
(-1548 3550);
DISPLAY 0.872340 (-1548 3550);
PAINT GREEN (-1548 3550);
DISPLAY INVISIBLE (-1548 3550);
FORCEADD TAP..1
R 2
(-1550 3500);
FORCEPROP 3 LASTPIN (-1500 3500) SIG_NAME P5E_CPU1_PE4_RX_DN<9>
J 0
(-1490 3510);
DISPLAY 0.659574 (-1490 3510);
PAINT MONO (-1490 3510);
DISPLAY INVISIBLE (-1490 3510);
FORCEPROP 1 LASTPIN (-1500 3500) BN 9
J 2
(-1488 3508);
DISPLAY 0.680851 (-1488 3508);
PAINT GREEN (-1488 3508);
FORCEPROP 2 LAST CDS_LIB standard
J 0
(-1550 3500);
DISPLAY INVISIBLE (-1550 3500);
FORCEPROP 1 LAST BODY_TYPE PLUMBING
J 2
(-1550 3550);
DISPLAY 0.872340 (-1550 3550);
PAINT GREEN (-1550 3550);
DISPLAY INVISIBLE (-1550 3550);
FORCEPROP 1 LAST HDL_TAP TRUE
J 2
(-1875 3375);
DISPLAY 0.872340 (-1875 3375);
DISPLAY INVISIBLE (-1875 3375);
FORCEPROP 1 LAST PATH I108
J 2
(-1548 3500);
DISPLAY 0.872340 (-1548 3500);
PAINT GREEN (-1548 3500);
DISPLAY INVISIBLE (-1548 3500);
FORCEADD TAP..1
R 2
(-1550 3600);
FORCEPROP 3 LASTPIN (-1500 3600) SIG_NAME P5E_CPU1_PE4_RX_DN<11>
J 0
(-1490 3610);
DISPLAY 0.659574 (-1490 3610);
PAINT MONO (-1490 3610);
DISPLAY INVISIBLE (-1490 3610);
FORCEPROP 1 LASTPIN (-1500 3600) BN 11
J 2
(-1488 3608);
DISPLAY 0.680851 (-1488 3608);
PAINT GREEN (-1488 3608);
FORCEPROP 2 LAST CDS_LIB standard
J 0
(-1550 3600);
DISPLAY INVISIBLE (-1550 3600);
FORCEPROP 1 LAST BODY_TYPE PLUMBING
J 2
(-1550 3650);
DISPLAY 0.872340 (-1550 3650);
PAINT GREEN (-1550 3650);
DISPLAY INVISIBLE (-1550 3650);
FORCEPROP 1 LAST HDL_TAP TRUE
J 2
(-1875 3475);
DISPLAY 0.872340 (-1875 3475);
DISPLAY INVISIBLE (-1875 3475);
FORCEPROP 1 LAST PATH I109
J 2
(-1548 3600);
DISPLAY 0.872340 (-1548 3600);
PAINT GREEN (-1548 3600);
DISPLAY INVISIBLE (-1548 3600);
FORCEADD TAP..1
R 2
(-1550 3700);
FORCEPROP 3 LASTPIN (-1500 3700) SIG_NAME P5E_CPU1_PE4_RX_DN<13>
J 0
(-1490 3710);
DISPLAY 0.659574 (-1490 3710);
PAINT MONO (-1490 3710);
DISPLAY INVISIBLE (-1490 3710);
FORCEPROP 1 LASTPIN (-1500 3700) BN 13
J 2
(-1488 3708);
DISPLAY 0.680851 (-1488 3708);
PAINT GREEN (-1488 3708);
FORCEPROP 2 LAST CDS_LIB standard
J 0
(-1550 3700);
DISPLAY INVISIBLE (-1550 3700);
FORCEPROP 1 LAST BODY_TYPE PLUMBING
J 2
(-1550 3750);
DISPLAY 0.872340 (-1550 3750);
PAINT GREEN (-1550 3750);
DISPLAY INVISIBLE (-1550 3750);
FORCEPROP 1 LAST HDL_TAP TRUE
J 2
(-1875 3575);
DISPLAY 0.872340 (-1875 3575);
DISPLAY INVISIBLE (-1875 3575);
FORCEPROP 1 LAST PATH I110
J 2
(-1548 3700);
DISPLAY 0.872340 (-1548 3700);
PAINT GREEN (-1548 3700);
DISPLAY INVISIBLE (-1548 3700);
FORCEADD TAP..1
R 2
(-1550 3650);
FORCEPROP 3 LASTPIN (-1500 3650) SIG_NAME P5E_CPU1_PE4_RX_DN<12>
J 0
(-1490 3660);
DISPLAY 0.659574 (-1490 3660);
PAINT MONO (-1490 3660);
DISPLAY INVISIBLE (-1490 3660);
FORCEPROP 1 LASTPIN (-1500 3650) BN 12
J 2
(-1488 3658);
DISPLAY 0.680851 (-1488 3658);
PAINT GREEN (-1488 3658);
FORCEPROP 2 LAST CDS_LIB standard
J 0
(-1550 3650);
DISPLAY INVISIBLE (-1550 3650);
FORCEPROP 1 LAST BODY_TYPE PLUMBING
J 2
(-1550 3700);
DISPLAY 0.872340 (-1550 3700);
PAINT GREEN (-1550 3700);
DISPLAY INVISIBLE (-1550 3700);
FORCEPROP 1 LAST HDL_TAP TRUE
J 2
(-1875 3525);
DISPLAY 0.872340 (-1875 3525);
DISPLAY INVISIBLE (-1875 3525);
FORCEPROP 1 LAST PATH I111
J 2
(-1548 3650);
DISPLAY 0.872340 (-1548 3650);
PAINT GREEN (-1548 3650);
DISPLAY INVISIBLE (-1548 3650);
FORCEADD TAP..1
R 2
(-1550 3750);
FORCEPROP 3 LASTPIN (-1500 3750) SIG_NAME P5E_CPU1_PE4_RX_DN<14>
J 0
(-1490 3760);
DISPLAY 0.659574 (-1490 3760);
PAINT MONO (-1490 3760);
DISPLAY INVISIBLE (-1490 3760);
FORCEPROP 1 LASTPIN (-1500 3750) BN 14
J 2
(-1488 3758);
DISPLAY 0.680851 (-1488 3758);
PAINT GREEN (-1488 3758);
FORCEPROP 2 LAST CDS_LIB standard
J 0
(-1550 3750);
DISPLAY INVISIBLE (-1550 3750);
FORCEPROP 1 LAST BODY_TYPE PLUMBING
J 2
(-1550 3800);
DISPLAY 0.872340 (-1550 3800);
PAINT GREEN (-1550 3800);
DISPLAY INVISIBLE (-1550 3800);
FORCEPROP 1 LAST HDL_TAP TRUE
J 2
(-1875 3625);
DISPLAY 0.872340 (-1875 3625);
DISPLAY INVISIBLE (-1875 3625);
FORCEPROP 1 LAST PATH I112
J 2
(-1548 3750);
DISPLAY 0.872340 (-1548 3750);
PAINT GREEN (-1548 3750);
DISPLAY INVISIBLE (-1548 3750);
FORCEADD TAP..1
R 2
(-1550 3800);
FORCEPROP 3 LASTPIN (-1500 3800) SIG_NAME P5E_CPU1_PE4_RX_DN<15>
J 0
(-1490 3810);
DISPLAY 0.659574 (-1490 3810);
PAINT MONO (-1490 3810);
DISPLAY INVISIBLE (-1490 3810);
FORCEPROP 1 LASTPIN (-1500 3800) BN 15
J 2
(-1488 3808);
DISPLAY 0.680851 (-1488 3808);
PAINT GREEN (-1488 3808);
FORCEPROP 2 LAST CDS_LIB standard
J 0
(-1550 3800);
DISPLAY INVISIBLE (-1550 3800);
FORCEPROP 1 LAST BODY_TYPE PLUMBING
J 2
(-1550 3850);
DISPLAY 0.872340 (-1550 3850);
PAINT GREEN (-1550 3850);
DISPLAY INVISIBLE (-1550 3850);
FORCEPROP 1 LAST HDL_TAP TRUE
J 2
(-1875 3675);
DISPLAY 0.872340 (-1875 3675);
DISPLAY INVISIBLE (-1875 3675);
FORCEPROP 1 LAST PATH I113
J 2
(-1548 3800);
DISPLAY 0.872340 (-1548 3800);
PAINT GREEN (-1548 3800);
DISPLAY INVISIBLE (-1548 3800);
FORCEADD TAP..1
R 2
(-1550 3900);
FORCEPROP 3 LASTPIN (-1500 3900) SIG_NAME P5E_CPU1_PE4_RX_DP<0>
J 0
(-1490 3910);
DISPLAY 0.659574 (-1490 3910);
PAINT MONO (-1490 3910);
DISPLAY INVISIBLE (-1490 3910);
FORCEPROP 1 LASTPIN (-1500 3900) BN 0
J 2
(-1488 3908);
DISPLAY 0.680851 (-1488 3908);
PAINT GREEN (-1488 3908);
FORCEPROP 2 LAST CDS_LIB standard
J 0
(-1550 3900);
DISPLAY INVISIBLE (-1550 3900);
FORCEPROP 1 LAST BODY_TYPE PLUMBING
J 2
(-1550 3950);
DISPLAY 0.872340 (-1550 3950);
PAINT GREEN (-1550 3950);
DISPLAY INVISIBLE (-1550 3950);
FORCEPROP 1 LAST HDL_TAP TRUE
J 2
(-1875 3775);
DISPLAY 0.872340 (-1875 3775);
DISPLAY INVISIBLE (-1875 3775);
FORCEPROP 1 LAST PATH I114
J 2
(-1548 3900);
DISPLAY 0.872340 (-1548 3900);
PAINT GREEN (-1548 3900);
DISPLAY INVISIBLE (-1548 3900);
FORCEADD TAP..1
R 2
(-1550 3950);
FORCEPROP 3 LASTPIN (-1500 3950) SIG_NAME P5E_CPU1_PE4_RX_DP<1>
J 0
(-1490 3960);
DISPLAY 0.659574 (-1490 3960);
PAINT MONO (-1490 3960);
DISPLAY INVISIBLE (-1490 3960);
FORCEPROP 1 LASTPIN (-1500 3950) BN 1
J 2
(-1488 3958);
DISPLAY 0.680851 (-1488 3958);
PAINT GREEN (-1488 3958);
FORCEPROP 2 LAST CDS_LIB standard
J 0
(-1550 3950);
DISPLAY INVISIBLE (-1550 3950);
FORCEPROP 1 LAST BODY_TYPE PLUMBING
J 2
(-1550 4000);
DISPLAY 0.872340 (-1550 4000);
PAINT GREEN (-1550 4000);
DISPLAY INVISIBLE (-1550 4000);
FORCEPROP 1 LAST HDL_TAP TRUE
J 2
(-1875 3825);
DISPLAY 0.872340 (-1875 3825);
DISPLAY INVISIBLE (-1875 3825);
FORCEPROP 1 LAST PATH I115
J 2
(-1548 3950);
DISPLAY 0.872340 (-1548 3950);
PAINT GREEN (-1548 3950);
DISPLAY INVISIBLE (-1548 3950);
FORCEADD TAP..1
R 2
(-1550 4000);
FORCEPROP 3 LASTPIN (-1500 4000) SIG_NAME P5E_CPU1_PE4_RX_DP<2>
J 0
(-1490 4010);
DISPLAY 0.659574 (-1490 4010);
PAINT MONO (-1490 4010);
DISPLAY INVISIBLE (-1490 4010);
FORCEPROP 1 LASTPIN (-1500 4000) BN 2
J 2
(-1488 4008);
DISPLAY 0.680851 (-1488 4008);
PAINT GREEN (-1488 4008);
FORCEPROP 2 LAST CDS_LIB standard
J 0
(-1550 4000);
DISPLAY INVISIBLE (-1550 4000);
FORCEPROP 1 LAST BODY_TYPE PLUMBING
J 2
(-1550 4050);
DISPLAY 0.872340 (-1550 4050);
PAINT GREEN (-1550 4050);
DISPLAY INVISIBLE (-1550 4050);
FORCEPROP 1 LAST HDL_TAP TRUE
J 2
(-1875 3875);
DISPLAY 0.872340 (-1875 3875);
DISPLAY INVISIBLE (-1875 3875);
FORCEPROP 1 LAST PATH I116
J 2
(-1548 4000);
DISPLAY 0.872340 (-1548 4000);
PAINT GREEN (-1548 4000);
DISPLAY INVISIBLE (-1548 4000);
FORCEADD TAP..1
R 2
(-1550 4050);
FORCEPROP 3 LASTPIN (-1500 4050) SIG_NAME P5E_CPU1_PE4_RX_DP<3>
J 0
(-1490 4060);
DISPLAY 0.659574 (-1490 4060);
PAINT MONO (-1490 4060);
DISPLAY INVISIBLE (-1490 4060);
FORCEPROP 1 LASTPIN (-1500 4050) BN 3
J 2
(-1488 4058);
DISPLAY 0.680851 (-1488 4058);
PAINT GREEN (-1488 4058);
FORCEPROP 2 LAST CDS_LIB standard
J 0
(-1550 4050);
DISPLAY INVISIBLE (-1550 4050);
FORCEPROP 1 LAST BODY_TYPE PLUMBING
J 2
(-1550 4100);
DISPLAY 0.872340 (-1550 4100);
PAINT GREEN (-1550 4100);
DISPLAY INVISIBLE (-1550 4100);
FORCEPROP 1 LAST HDL_TAP TRUE
J 2
(-1875 3925);
DISPLAY 0.872340 (-1875 3925);
DISPLAY INVISIBLE (-1875 3925);
FORCEPROP 1 LAST PATH I117
J 2
(-1548 4050);
DISPLAY 0.872340 (-1548 4050);
PAINT GREEN (-1548 4050);
DISPLAY INVISIBLE (-1548 4050);
FORCEADD TAP..1
R 2
(-1550 4100);
FORCEPROP 3 LASTPIN (-1500 4100) SIG_NAME P5E_CPU1_PE4_RX_DP<4>
J 0
(-1490 4110);
DISPLAY 0.659574 (-1490 4110);
PAINT MONO (-1490 4110);
DISPLAY INVISIBLE (-1490 4110);
FORCEPROP 1 LASTPIN (-1500 4100) BN 4
J 2
(-1488 4108);
DISPLAY 0.680851 (-1488 4108);
PAINT GREEN (-1488 4108);
FORCEPROP 2 LAST CDS_LIB standard
J 0
(-1550 4100);
DISPLAY INVISIBLE (-1550 4100);
FORCEPROP 1 LAST BODY_TYPE PLUMBING
J 2
(-1550 4150);
DISPLAY 0.872340 (-1550 4150);
PAINT GREEN (-1550 4150);
DISPLAY INVISIBLE (-1550 4150);
FORCEPROP 1 LAST HDL_TAP TRUE
J 2
(-1875 3975);
DISPLAY 0.872340 (-1875 3975);
DISPLAY INVISIBLE (-1875 3975);
FORCEPROP 1 LAST PATH I118
J 2
(-1548 4100);
DISPLAY 0.872340 (-1548 4100);
PAINT GREEN (-1548 4100);
DISPLAY INVISIBLE (-1548 4100);
FORCEADD TAP..1
R 2
(-1550 4150);
FORCEPROP 3 LASTPIN (-1500 4150) SIG_NAME P5E_CPU1_PE4_RX_DP<5>
J 0
(-1490 4160);
DISPLAY 0.659574 (-1490 4160);
PAINT MONO (-1490 4160);
DISPLAY INVISIBLE (-1490 4160);
FORCEPROP 1 LASTPIN (-1500 4150) BN 5
J 2
(-1488 4158);
DISPLAY 0.680851 (-1488 4158);
PAINT GREEN (-1488 4158);
FORCEPROP 2 LAST CDS_LIB standard
J 0
(-1550 4150);
DISPLAY INVISIBLE (-1550 4150);
FORCEPROP 1 LAST BODY_TYPE PLUMBING
J 2
(-1550 4200);
DISPLAY 0.872340 (-1550 4200);
PAINT GREEN (-1550 4200);
DISPLAY INVISIBLE (-1550 4200);
FORCEPROP 1 LAST HDL_TAP TRUE
J 2
(-1875 4025);
DISPLAY 0.872340 (-1875 4025);
DISPLAY INVISIBLE (-1875 4025);
FORCEPROP 1 LAST PATH I119
J 2
(-1548 4150);
DISPLAY 0.872340 (-1548 4150);
PAINT GREEN (-1548 4150);
DISPLAY INVISIBLE (-1548 4150);
FORCEADD TAP..1
R 2
(-1550 4200);
FORCEPROP 3 LASTPIN (-1500 4200) SIG_NAME P5E_CPU1_PE4_RX_DP<6>
J 0
(-1490 4210);
DISPLAY 0.659574 (-1490 4210);
PAINT MONO (-1490 4210);
DISPLAY INVISIBLE (-1490 4210);
FORCEPROP 1 LASTPIN (-1500 4200) BN 6
J 2
(-1488 4208);
DISPLAY 0.680851 (-1488 4208);
PAINT GREEN (-1488 4208);
FORCEPROP 2 LAST CDS_LIB standard
J 0
(-1550 4200);
DISPLAY INVISIBLE (-1550 4200);
FORCEPROP 1 LAST BODY_TYPE PLUMBING
J 2
(-1550 4250);
DISPLAY 0.872340 (-1550 4250);
PAINT GREEN (-1550 4250);
DISPLAY INVISIBLE (-1550 4250);
FORCEPROP 1 LAST HDL_TAP TRUE
J 2
(-1875 4075);
DISPLAY 0.872340 (-1875 4075);
DISPLAY INVISIBLE (-1875 4075);
FORCEPROP 1 LAST PATH I120
J 2
(-1548 4200);
DISPLAY 0.872340 (-1548 4200);
PAINT GREEN (-1548 4200);
DISPLAY INVISIBLE (-1548 4200);
FORCEADD TAP..1
R 2
(-1550 4250);
FORCEPROP 3 LASTPIN (-1500 4250) SIG_NAME P5E_CPU1_PE4_RX_DP<7>
J 0
(-1490 4260);
DISPLAY 0.659574 (-1490 4260);
PAINT MONO (-1490 4260);
DISPLAY INVISIBLE (-1490 4260);
FORCEPROP 1 LASTPIN (-1500 4250) BN 7
J 2
(-1488 4258);
DISPLAY 0.680851 (-1488 4258);
PAINT GREEN (-1488 4258);
FORCEPROP 2 LAST CDS_LIB standard
J 0
(-1550 4250);
DISPLAY INVISIBLE (-1550 4250);
FORCEPROP 1 LAST BODY_TYPE PLUMBING
J 2
(-1550 4300);
DISPLAY 0.872340 (-1550 4300);
PAINT GREEN (-1550 4300);
DISPLAY INVISIBLE (-1550 4300);
FORCEPROP 1 LAST HDL_TAP TRUE
J 2
(-1875 4125);
DISPLAY 0.872340 (-1875 4125);
DISPLAY INVISIBLE (-1875 4125);
FORCEPROP 1 LAST PATH I121
J 2
(-1548 4250);
DISPLAY 0.872340 (-1548 4250);
PAINT GREEN (-1548 4250);
DISPLAY INVISIBLE (-1548 4250);
FORCEADD TAP..1
R 2
(-1550 4300);
FORCEPROP 3 LASTPIN (-1500 4300) SIG_NAME P5E_CPU1_PE4_RX_DP<8>
J 0
(-1490 4310);
DISPLAY 0.659574 (-1490 4310);
PAINT MONO (-1490 4310);
DISPLAY INVISIBLE (-1490 4310);
FORCEPROP 1 LASTPIN (-1500 4300) BN 8
J 2
(-1488 4308);
DISPLAY 0.680851 (-1488 4308);
PAINT GREEN (-1488 4308);
FORCEPROP 2 LAST CDS_LIB standard
J 0
(-1550 4300);
DISPLAY INVISIBLE (-1550 4300);
FORCEPROP 1 LAST BODY_TYPE PLUMBING
J 2
(-1550 4350);
DISPLAY 0.872340 (-1550 4350);
PAINT GREEN (-1550 4350);
DISPLAY INVISIBLE (-1550 4350);
FORCEPROP 1 LAST HDL_TAP TRUE
J 2
(-1875 4175);
DISPLAY 0.872340 (-1875 4175);
DISPLAY INVISIBLE (-1875 4175);
FORCEPROP 1 LAST PATH I122
J 2
(-1548 4300);
DISPLAY 0.872340 (-1548 4300);
PAINT GREEN (-1548 4300);
DISPLAY INVISIBLE (-1548 4300);
FORCEADD TAP..1
R 2
(-1550 4350);
FORCEPROP 3 LASTPIN (-1500 4350) SIG_NAME P5E_CPU1_PE4_RX_DP<9>
J 0
(-1490 4360);
DISPLAY 0.659574 (-1490 4360);
PAINT MONO (-1490 4360);
DISPLAY INVISIBLE (-1490 4360);
FORCEPROP 1 LASTPIN (-1500 4350) BN 9
J 2
(-1488 4358);
DISPLAY 0.680851 (-1488 4358);
PAINT GREEN (-1488 4358);
FORCEPROP 2 LAST CDS_LIB standard
J 0
(-1550 4350);
DISPLAY INVISIBLE (-1550 4350);
FORCEPROP 1 LAST BODY_TYPE PLUMBING
J 2
(-1550 4400);
DISPLAY 0.872340 (-1550 4400);
PAINT GREEN (-1550 4400);
DISPLAY INVISIBLE (-1550 4400);
FORCEPROP 1 LAST HDL_TAP TRUE
J 2
(-1875 4225);
DISPLAY 0.872340 (-1875 4225);
DISPLAY INVISIBLE (-1875 4225);
FORCEPROP 1 LAST PATH I123
J 2
(-1548 4350);
DISPLAY 0.872340 (-1548 4350);
PAINT GREEN (-1548 4350);
DISPLAY INVISIBLE (-1548 4350);
FORCEADD TAP..1
R 2
(-1550 4400);
FORCEPROP 3 LASTPIN (-1500 4400) SIG_NAME P5E_CPU1_PE4_RX_DP<10>
J 0
(-1490 4410);
DISPLAY 0.659574 (-1490 4410);
PAINT MONO (-1490 4410);
DISPLAY INVISIBLE (-1490 4410);
FORCEPROP 1 LASTPIN (-1500 4400) BN 10
J 2
(-1488 4408);
DISPLAY 0.680851 (-1488 4408);
PAINT GREEN (-1488 4408);
FORCEPROP 2 LAST CDS_LIB standard
J 0
(-1550 4400);
DISPLAY INVISIBLE (-1550 4400);
FORCEPROP 1 LAST BODY_TYPE PLUMBING
J 2
(-1550 4450);
DISPLAY 0.872340 (-1550 4450);
PAINT GREEN (-1550 4450);
DISPLAY INVISIBLE (-1550 4450);
FORCEPROP 1 LAST HDL_TAP TRUE
J 2
(-1875 4275);
DISPLAY 0.872340 (-1875 4275);
DISPLAY INVISIBLE (-1875 4275);
FORCEPROP 1 LAST PATH I124
J 2
(-1548 4400);
DISPLAY 0.872340 (-1548 4400);
PAINT GREEN (-1548 4400);
DISPLAY INVISIBLE (-1548 4400);
FORCEADD TAP..1
R 2
(-1550 4450);
FORCEPROP 3 LASTPIN (-1500 4450) SIG_NAME P5E_CPU1_PE4_RX_DP<11>
J 0
(-1490 4460);
DISPLAY 0.659574 (-1490 4460);
PAINT MONO (-1490 4460);
DISPLAY INVISIBLE (-1490 4460);
FORCEPROP 1 LASTPIN (-1500 4450) BN 11
J 2
(-1488 4458);
DISPLAY 0.680851 (-1488 4458);
PAINT GREEN (-1488 4458);
FORCEPROP 2 LAST CDS_LIB standard
J 0
(-1550 4450);
DISPLAY INVISIBLE (-1550 4450);
FORCEPROP 1 LAST BODY_TYPE PLUMBING
J 2
(-1550 4500);
DISPLAY 0.872340 (-1550 4500);
PAINT GREEN (-1550 4500);
DISPLAY INVISIBLE (-1550 4500);
FORCEPROP 1 LAST HDL_TAP TRUE
J 2
(-1875 4325);
DISPLAY 0.872340 (-1875 4325);
DISPLAY INVISIBLE (-1875 4325);
FORCEPROP 1 LAST PATH I125
J 2
(-1548 4450);
DISPLAY 0.872340 (-1548 4450);
PAINT GREEN (-1548 4450);
DISPLAY INVISIBLE (-1548 4450);
FORCEADD TAP..1
R 2
(-1550 4500);
FORCEPROP 3 LASTPIN (-1500 4500) SIG_NAME P5E_CPU1_PE4_RX_DP<12>
J 0
(-1490 4510);
DISPLAY 0.659574 (-1490 4510);
PAINT MONO (-1490 4510);
DISPLAY INVISIBLE (-1490 4510);
FORCEPROP 1 LASTPIN (-1500 4500) BN 12
J 2
(-1488 4508);
DISPLAY 0.680851 (-1488 4508);
PAINT GREEN (-1488 4508);
FORCEPROP 2 LAST CDS_LIB standard
J 0
(-1550 4500);
DISPLAY INVISIBLE (-1550 4500);
FORCEPROP 1 LAST BODY_TYPE PLUMBING
J 2
(-1550 4550);
DISPLAY 0.872340 (-1550 4550);
PAINT GREEN (-1550 4550);
DISPLAY INVISIBLE (-1550 4550);
FORCEPROP 1 LAST HDL_TAP TRUE
J 2
(-1875 4375);
DISPLAY 0.872340 (-1875 4375);
DISPLAY INVISIBLE (-1875 4375);
FORCEPROP 1 LAST PATH I126
J 2
(-1548 4500);
DISPLAY 0.872340 (-1548 4500);
PAINT GREEN (-1548 4500);
DISPLAY INVISIBLE (-1548 4500);
FORCEADD TAP..1
R 2
(-1550 4550);
FORCEPROP 3 LASTPIN (-1500 4550) SIG_NAME P5E_CPU1_PE4_RX_DP<13>
J 0
(-1490 4560);
DISPLAY 0.659574 (-1490 4560);
PAINT MONO (-1490 4560);
DISPLAY INVISIBLE (-1490 4560);
FORCEPROP 1 LASTPIN (-1500 4550) BN 13
J 2
(-1488 4558);
DISPLAY 0.680851 (-1488 4558);
PAINT GREEN (-1488 4558);
FORCEPROP 2 LAST CDS_LIB standard
J 0
(-1550 4550);
DISPLAY INVISIBLE (-1550 4550);
FORCEPROP 1 LAST BODY_TYPE PLUMBING
J 2
(-1550 4600);
DISPLAY 0.872340 (-1550 4600);
PAINT GREEN (-1550 4600);
DISPLAY INVISIBLE (-1550 4600);
FORCEPROP 1 LAST HDL_TAP TRUE
J 2
(-1875 4425);
DISPLAY 0.872340 (-1875 4425);
DISPLAY INVISIBLE (-1875 4425);
FORCEPROP 1 LAST PATH I127
J 2
(-1548 4550);
DISPLAY 0.872340 (-1548 4550);
PAINT GREEN (-1548 4550);
DISPLAY INVISIBLE (-1548 4550);
FORCEADD TAP..1
R 2
(-1550 4600);
FORCEPROP 3 LASTPIN (-1500 4600) SIG_NAME P5E_CPU1_PE4_RX_DP<14>
J 0
(-1490 4610);
DISPLAY 0.659574 (-1490 4610);
PAINT MONO (-1490 4610);
DISPLAY INVISIBLE (-1490 4610);
FORCEPROP 1 LASTPIN (-1500 4600) BN 14
J 2
(-1488 4608);
DISPLAY 0.680851 (-1488 4608);
PAINT GREEN (-1488 4608);
FORCEPROP 2 LAST CDS_LIB standard
J 0
(-1550 4600);
DISPLAY INVISIBLE (-1550 4600);
FORCEPROP 1 LAST BODY_TYPE PLUMBING
J 2
(-1550 4650);
DISPLAY 0.872340 (-1550 4650);
PAINT GREEN (-1550 4650);
DISPLAY INVISIBLE (-1550 4650);
FORCEPROP 1 LAST HDL_TAP TRUE
J 2
(-1875 4475);
DISPLAY 0.872340 (-1875 4475);
DISPLAY INVISIBLE (-1875 4475);
FORCEPROP 1 LAST PATH I128
J 2
(-1548 4600);
DISPLAY 0.872340 (-1548 4600);
PAINT GREEN (-1548 4600);
DISPLAY INVISIBLE (-1548 4600);
FORCEADD TAP..1
R 2
(-1550 4650);
FORCEPROP 3 LASTPIN (-1500 4650) SIG_NAME P5E_CPU1_PE4_RX_DP<15>
J 0
(-1490 4660);
DISPLAY 0.659574 (-1490 4660);
PAINT MONO (-1490 4660);
DISPLAY INVISIBLE (-1490 4660);
FORCEPROP 1 LASTPIN (-1500 4650) BN 15
J 2
(-1488 4658);
DISPLAY 0.680851 (-1488 4658);
PAINT GREEN (-1488 4658);
FORCEPROP 2 LAST CDS_LIB standard
J 0
(-1550 4650);
DISPLAY INVISIBLE (-1550 4650);
FORCEPROP 1 LAST BODY_TYPE PLUMBING
J 2
(-1550 4700);
DISPLAY 0.872340 (-1550 4700);
PAINT GREEN (-1550 4700);
DISPLAY INVISIBLE (-1550 4700);
FORCEPROP 1 LAST HDL_TAP TRUE
J 2
(-1875 4525);
DISPLAY 0.872340 (-1875 4525);
DISPLAY INVISIBLE (-1875 4525);
FORCEPROP 1 LAST PATH I129
J 2
(-1548 4650);
DISPLAY 0.872340 (-1548 4650);
PAINT GREEN (-1548 4650);
DISPLAY INVISIBLE (-1548 4650);
FORCEADD TAP..1
(1800 3050);
FORCEPROP 3 LASTPIN (1750 3050) SIG_NAME P5E_CPU1_PE4_TX_DN<0>
J 0
(1760 3060);
DISPLAY 0.659574 (1760 3060);
PAINT MONO (1760 3060);
DISPLAY INVISIBLE (1760 3060);
FORCEPROP 1 LASTPIN (1750 3050) BN 0
J 0
(1738 3058);
DISPLAY 0.680851 (1738 3058);
PAINT GREEN (1738 3058);
FORCEPROP 2 LAST CDS_LIB standard
J 0
(1800 3050);
PAINT MONO (1800 3050);
DISPLAY INVISIBLE (1800 3050);
FORCEPROP 1 LAST BODY_TYPE PLUMBING
J 0
(1800 3100);
DISPLAY 0.872340 (1800 3100);
PAINT GREEN (1800 3100);
DISPLAY INVISIBLE (1800 3100);
FORCEPROP 1 LAST HDL_TAP TRUE
J 0
(2125 2925);
DISPLAY 0.872340 (2125 2925);
DISPLAY INVISIBLE (2125 2925);
FORCEPROP 1 LAST PATH I130
J 0
(1798 3050);
DISPLAY 0.872340 (1798 3050);
PAINT GREEN (1798 3050);
DISPLAY INVISIBLE (1798 3050);
FORCEADD TAP..1
(1800 3150);
FORCEPROP 3 LASTPIN (1750 3150) SIG_NAME P5E_CPU1_PE4_TX_DN<2>
J 0
(1760 3160);
DISPLAY 0.659574 (1760 3160);
PAINT MONO (1760 3160);
DISPLAY INVISIBLE (1760 3160);
FORCEPROP 1 LASTPIN (1750 3150) BN 2
J 0
(1738 3158);
DISPLAY 0.680851 (1738 3158);
PAINT GREEN (1738 3158);
FORCEPROP 2 LAST CDS_LIB standard
J 0
(1800 3150);
PAINT MONO (1800 3150);
DISPLAY INVISIBLE (1800 3150);
FORCEPROP 1 LAST BODY_TYPE PLUMBING
J 0
(1800 3200);
DISPLAY 0.872340 (1800 3200);
PAINT GREEN (1800 3200);
DISPLAY INVISIBLE (1800 3200);
FORCEPROP 1 LAST HDL_TAP TRUE
J 0
(2125 3025);
DISPLAY 0.872340 (2125 3025);
DISPLAY INVISIBLE (2125 3025);
FORCEPROP 1 LAST PATH I131
J 0
(1798 3150);
DISPLAY 0.872340 (1798 3150);
PAINT GREEN (1798 3150);
DISPLAY INVISIBLE (1798 3150);
FORCEADD TAP..1
(1800 3100);
FORCEPROP 3 LASTPIN (1750 3100) SIG_NAME P5E_CPU1_PE4_TX_DN<1>
J 0
(1760 3110);
DISPLAY 0.659574 (1760 3110);
PAINT MONO (1760 3110);
DISPLAY INVISIBLE (1760 3110);
FORCEPROP 1 LASTPIN (1750 3100) BN 1
J 0
(1738 3108);
DISPLAY 0.680851 (1738 3108);
PAINT GREEN (1738 3108);
FORCEPROP 2 LAST CDS_LIB standard
J 0
(1800 3100);
PAINT MONO (1800 3100);
DISPLAY INVISIBLE (1800 3100);
FORCEPROP 1 LAST BODY_TYPE PLUMBING
J 0
(1800 3150);
DISPLAY 0.872340 (1800 3150);
PAINT GREEN (1800 3150);
DISPLAY INVISIBLE (1800 3150);
FORCEPROP 1 LAST HDL_TAP TRUE
J 0
(2125 2975);
DISPLAY 0.872340 (2125 2975);
DISPLAY INVISIBLE (2125 2975);
FORCEPROP 1 LAST PATH I132
J 0
(1798 3100);
DISPLAY 0.872340 (1798 3100);
PAINT GREEN (1798 3100);
DISPLAY INVISIBLE (1798 3100);
FORCEADD TAP..1
(1800 3200);
FORCEPROP 3 LASTPIN (1750 3200) SIG_NAME P5E_CPU1_PE4_TX_DN<3>
J 0
(1760 3210);
DISPLAY 0.659574 (1760 3210);
PAINT MONO (1760 3210);
DISPLAY INVISIBLE (1760 3210);
FORCEPROP 1 LASTPIN (1750 3200) BN 3
J 0
(1738 3208);
DISPLAY 0.680851 (1738 3208);
PAINT GREEN (1738 3208);
FORCEPROP 2 LAST CDS_LIB standard
J 0
(1800 3200);
PAINT MONO (1800 3200);
DISPLAY INVISIBLE (1800 3200);
FORCEPROP 1 LAST BODY_TYPE PLUMBING
J 0
(1800 3250);
DISPLAY 0.872340 (1800 3250);
PAINT GREEN (1800 3250);
DISPLAY INVISIBLE (1800 3250);
FORCEPROP 1 LAST HDL_TAP TRUE
J 0
(2125 3075);
DISPLAY 0.872340 (2125 3075);
DISPLAY INVISIBLE (2125 3075);
FORCEPROP 1 LAST PATH I133
J 0
(1798 3200);
DISPLAY 0.872340 (1798 3200);
PAINT GREEN (1798 3200);
DISPLAY INVISIBLE (1798 3200);
FORCEADD TAP..1
(1800 3250);
FORCEPROP 3 LASTPIN (1750 3250) SIG_NAME P5E_CPU1_PE4_TX_DN<4>
J 0
(1760 3260);
DISPLAY 0.659574 (1760 3260);
PAINT MONO (1760 3260);
DISPLAY INVISIBLE (1760 3260);
FORCEPROP 1 LASTPIN (1750 3250) BN 4
J 0
(1738 3258);
DISPLAY 0.680851 (1738 3258);
PAINT GREEN (1738 3258);
FORCEPROP 2 LAST CDS_LIB standard
J 0
(1800 3250);
PAINT MONO (1800 3250);
DISPLAY INVISIBLE (1800 3250);
FORCEPROP 1 LAST BODY_TYPE PLUMBING
J 0
(1800 3300);
DISPLAY 0.872340 (1800 3300);
PAINT GREEN (1800 3300);
DISPLAY INVISIBLE (1800 3300);
FORCEPROP 1 LAST HDL_TAP TRUE
J 0
(2125 3125);
DISPLAY 0.872340 (2125 3125);
DISPLAY INVISIBLE (2125 3125);
FORCEPROP 1 LAST PATH I134
J 0
(1798 3250);
DISPLAY 0.872340 (1798 3250);
PAINT GREEN (1798 3250);
DISPLAY INVISIBLE (1798 3250);
FORCEADD TAP..1
(1800 3300);
FORCEPROP 3 LASTPIN (1750 3300) SIG_NAME P5E_CPU1_PE4_TX_DN<5>
J 0
(1760 3310);
DISPLAY 0.659574 (1760 3310);
PAINT MONO (1760 3310);
DISPLAY INVISIBLE (1760 3310);
FORCEPROP 1 LASTPIN (1750 3300) BN 5
J 0
(1738 3308);
DISPLAY 0.680851 (1738 3308);
PAINT GREEN (1738 3308);
FORCEPROP 2 LAST CDS_LIB standard
J 0
(1800 3300);
PAINT MONO (1800 3300);
DISPLAY INVISIBLE (1800 3300);
FORCEPROP 1 LAST BODY_TYPE PLUMBING
J 0
(1800 3350);
DISPLAY 0.872340 (1800 3350);
PAINT GREEN (1800 3350);
DISPLAY INVISIBLE (1800 3350);
FORCEPROP 1 LAST HDL_TAP TRUE
J 0
(2125 3175);
DISPLAY 0.872340 (2125 3175);
DISPLAY INVISIBLE (2125 3175);
FORCEPROP 1 LAST PATH I135
J 0
(1798 3300);
DISPLAY 0.872340 (1798 3300);
PAINT GREEN (1798 3300);
DISPLAY INVISIBLE (1798 3300);
FORCEADD TAP..1
(1800 3400);
FORCEPROP 3 LASTPIN (1750 3400) SIG_NAME P5E_CPU1_PE4_TX_DN<7>
J 0
(1760 3410);
DISPLAY 0.659574 (1760 3410);
PAINT MONO (1760 3410);
DISPLAY INVISIBLE (1760 3410);
FORCEPROP 1 LASTPIN (1750 3400) BN 7
J 0
(1738 3408);
DISPLAY 0.680851 (1738 3408);
PAINT GREEN (1738 3408);
FORCEPROP 2 LAST CDS_LIB standard
J 0
(1800 3400);
PAINT MONO (1800 3400);
DISPLAY INVISIBLE (1800 3400);
FORCEPROP 1 LAST BODY_TYPE PLUMBING
J 0
(1800 3450);
DISPLAY 0.872340 (1800 3450);
PAINT GREEN (1800 3450);
DISPLAY INVISIBLE (1800 3450);
FORCEPROP 1 LAST HDL_TAP TRUE
J 0
(2125 3275);
DISPLAY 0.872340 (2125 3275);
DISPLAY INVISIBLE (2125 3275);
FORCEPROP 1 LAST PATH I136
J 0
(1798 3400);
DISPLAY 0.872340 (1798 3400);
PAINT GREEN (1798 3400);
DISPLAY INVISIBLE (1798 3400);
FORCEADD TAP..1
(1800 3350);
FORCEPROP 3 LASTPIN (1750 3350) SIG_NAME P5E_CPU1_PE4_TX_DN<6>
J 0
(1760 3360);
DISPLAY 0.659574 (1760 3360);
PAINT MONO (1760 3360);
DISPLAY INVISIBLE (1760 3360);
FORCEPROP 1 LASTPIN (1750 3350) BN 6
J 0
(1738 3358);
DISPLAY 0.680851 (1738 3358);
PAINT GREEN (1738 3358);
FORCEPROP 2 LAST CDS_LIB standard
J 0
(1800 3350);
PAINT MONO (1800 3350);
DISPLAY INVISIBLE (1800 3350);
FORCEPROP 1 LAST BODY_TYPE PLUMBING
J 0
(1800 3400);
DISPLAY 0.872340 (1800 3400);
PAINT GREEN (1800 3400);
DISPLAY INVISIBLE (1800 3400);
FORCEPROP 1 LAST HDL_TAP TRUE
J 0
(2125 3225);
DISPLAY 0.872340 (2125 3225);
DISPLAY INVISIBLE (2125 3225);
FORCEPROP 1 LAST PATH I137
J 0
(1798 3350);
DISPLAY 0.872340 (1798 3350);
PAINT GREEN (1798 3350);
DISPLAY INVISIBLE (1798 3350);
FORCEADD TAP..1
(1800 3450);
FORCEPROP 3 LASTPIN (1750 3450) SIG_NAME P5E_CPU1_PE4_TX_DN<8>
J 0
(1760 3460);
DISPLAY 0.659574 (1760 3460);
PAINT MONO (1760 3460);
DISPLAY INVISIBLE (1760 3460);
FORCEPROP 1 LASTPIN (1750 3450) BN 8
J 0
(1738 3458);
DISPLAY 0.680851 (1738 3458);
PAINT GREEN (1738 3458);
FORCEPROP 2 LAST CDS_LIB standard
J 0
(1800 3450);
PAINT MONO (1800 3450);
DISPLAY INVISIBLE (1800 3450);
FORCEPROP 1 LAST BODY_TYPE PLUMBING
J 0
(1800 3500);
DISPLAY 0.872340 (1800 3500);
PAINT GREEN (1800 3500);
DISPLAY INVISIBLE (1800 3500);
FORCEPROP 1 LAST HDL_TAP TRUE
J 0
(2125 3325);
DISPLAY 0.872340 (2125 3325);
DISPLAY INVISIBLE (2125 3325);
FORCEPROP 1 LAST PATH I138
J 0
(1798 3450);
DISPLAY 0.872340 (1798 3450);
PAINT GREEN (1798 3450);
DISPLAY INVISIBLE (1798 3450);
FORCEADD TAP..1
(1800 3550);
FORCEPROP 3 LASTPIN (1750 3550) SIG_NAME P5E_CPU1_PE4_TX_DN<10>
J 0
(1760 3560);
DISPLAY 0.659574 (1760 3560);
PAINT MONO (1760 3560);
DISPLAY INVISIBLE (1760 3560);
FORCEPROP 1 LASTPIN (1750 3550) BN 10
J 0
(1738 3558);
DISPLAY 0.680851 (1738 3558);
PAINT GREEN (1738 3558);
FORCEPROP 2 LAST CDS_LIB standard
J 0
(1800 3550);
DISPLAY INVISIBLE (1800 3550);
FORCEPROP 1 LAST BODY_TYPE PLUMBING
J 0
(1800 3600);
DISPLAY 0.872340 (1800 3600);
PAINT GREEN (1800 3600);
DISPLAY INVISIBLE (1800 3600);
FORCEPROP 1 LAST HDL_TAP TRUE
J 0
(2125 3425);
DISPLAY 0.872340 (2125 3425);
DISPLAY INVISIBLE (2125 3425);
FORCEPROP 1 LAST PATH I139
J 0
(1798 3550);
DISPLAY 0.872340 (1798 3550);
PAINT GREEN (1798 3550);
DISPLAY INVISIBLE (1798 3550);
FORCEADD TAP..1
(1800 3500);
FORCEPROP 3 LASTPIN (1750 3500) SIG_NAME P5E_CPU1_PE4_TX_DN<9>
J 0
(1760 3510);
DISPLAY 0.659574 (1760 3510);
PAINT MONO (1760 3510);
DISPLAY INVISIBLE (1760 3510);
FORCEPROP 1 LASTPIN (1750 3500) BN 9
J 0
(1738 3508);
DISPLAY 0.680851 (1738 3508);
PAINT GREEN (1738 3508);
FORCEPROP 2 LAST CDS_LIB standard
J 0
(1800 3500);
DISPLAY INVISIBLE (1800 3500);
FORCEPROP 1 LAST BODY_TYPE PLUMBING
J 0
(1800 3550);
DISPLAY 0.872340 (1800 3550);
PAINT GREEN (1800 3550);
DISPLAY INVISIBLE (1800 3550);
FORCEPROP 1 LAST HDL_TAP TRUE
J 0
(2125 3375);
DISPLAY 0.872340 (2125 3375);
DISPLAY INVISIBLE (2125 3375);
FORCEPROP 1 LAST PATH I140
J 0
(1798 3500);
DISPLAY 0.872340 (1798 3500);
PAINT GREEN (1798 3500);
DISPLAY INVISIBLE (1798 3500);
FORCEADD TAP..1
(1800 3700);
FORCEPROP 3 LASTPIN (1750 3700) SIG_NAME P5E_CPU1_PE4_TX_DN<13>
J 0
(1760 3710);
DISPLAY 0.659574 (1760 3710);
PAINT MONO (1760 3710);
DISPLAY INVISIBLE (1760 3710);
FORCEPROP 1 LASTPIN (1750 3700) BN 13
J 0
(1738 3708);
DISPLAY 0.680851 (1738 3708);
PAINT GREEN (1738 3708);
FORCEPROP 2 LAST CDS_LIB standard
J 0
(1800 3700);
DISPLAY INVISIBLE (1800 3700);
FORCEPROP 1 LAST BODY_TYPE PLUMBING
J 0
(1800 3750);
DISPLAY 0.872340 (1800 3750);
PAINT GREEN (1800 3750);
DISPLAY INVISIBLE (1800 3750);
FORCEPROP 1 LAST HDL_TAP TRUE
J 0
(2125 3575);
DISPLAY 0.872340 (2125 3575);
DISPLAY INVISIBLE (2125 3575);
FORCEPROP 1 LAST PATH I141
J 0
(1798 3700);
DISPLAY 0.872340 (1798 3700);
PAINT GREEN (1798 3700);
DISPLAY INVISIBLE (1798 3700);
FORCEADD TAP..1
(1800 3650);
FORCEPROP 3 LASTPIN (1750 3650) SIG_NAME P5E_CPU1_PE4_TX_DN<12>
J 0
(1760 3660);
DISPLAY 0.659574 (1760 3660);
PAINT MONO (1760 3660);
DISPLAY INVISIBLE (1760 3660);
FORCEPROP 1 LASTPIN (1750 3650) BN 12
J 0
(1738 3658);
DISPLAY 0.680851 (1738 3658);
PAINT GREEN (1738 3658);
FORCEPROP 2 LAST CDS_LIB standard
J 0
(1800 3650);
DISPLAY INVISIBLE (1800 3650);
FORCEPROP 1 LAST BODY_TYPE PLUMBING
J 0
(1800 3700);
DISPLAY 0.872340 (1800 3700);
PAINT GREEN (1800 3700);
DISPLAY INVISIBLE (1800 3700);
FORCEPROP 1 LAST HDL_TAP TRUE
J 0
(2125 3525);
DISPLAY 0.872340 (2125 3525);
DISPLAY INVISIBLE (2125 3525);
FORCEPROP 1 LAST PATH I142
J 0
(1798 3650);
DISPLAY 0.872340 (1798 3650);
PAINT GREEN (1798 3650);
DISPLAY INVISIBLE (1798 3650);
FORCEADD TAP..1
(1800 3600);
FORCEPROP 3 LASTPIN (1750 3600) SIG_NAME P5E_CPU1_PE4_TX_DN<11>
J 0
(1760 3610);
DISPLAY 0.659574 (1760 3610);
PAINT MONO (1760 3610);
DISPLAY INVISIBLE (1760 3610);
FORCEPROP 1 LASTPIN (1750 3600) BN 11
J 0
(1738 3608);
DISPLAY 0.680851 (1738 3608);
PAINT GREEN (1738 3608);
FORCEPROP 2 LAST CDS_LIB standard
J 0
(1800 3600);
DISPLAY INVISIBLE (1800 3600);
FORCEPROP 1 LAST BODY_TYPE PLUMBING
J 0
(1800 3650);
DISPLAY 0.872340 (1800 3650);
PAINT GREEN (1800 3650);
DISPLAY INVISIBLE (1800 3650);
FORCEPROP 1 LAST HDL_TAP TRUE
J 0
(2125 3475);
DISPLAY 0.872340 (2125 3475);
DISPLAY INVISIBLE (2125 3475);
FORCEPROP 1 LAST PATH I143
J 0
(1798 3600);
DISPLAY 0.872340 (1798 3600);
PAINT GREEN (1798 3600);
DISPLAY INVISIBLE (1798 3600);
FORCEADD TAP..1
(1800 3800);
FORCEPROP 3 LASTPIN (1750 3800) SIG_NAME P5E_CPU1_PE4_TX_DN<15>
J 0
(1760 3810);
DISPLAY 0.659574 (1760 3810);
PAINT MONO (1760 3810);
DISPLAY INVISIBLE (1760 3810);
FORCEPROP 1 LASTPIN (1750 3800) BN 15
J 0
(1738 3808);
DISPLAY 0.680851 (1738 3808);
PAINT GREEN (1738 3808);
FORCEPROP 2 LAST CDS_LIB standard
J 0
(1800 3800);
DISPLAY INVISIBLE (1800 3800);
FORCEPROP 1 LAST BODY_TYPE PLUMBING
J 0
(1800 3850);
DISPLAY 0.872340 (1800 3850);
PAINT GREEN (1800 3850);
DISPLAY INVISIBLE (1800 3850);
FORCEPROP 1 LAST HDL_TAP TRUE
J 0
(2125 3675);
DISPLAY 0.872340 (2125 3675);
DISPLAY INVISIBLE (2125 3675);
FORCEPROP 1 LAST PATH I144
J 0
(1798 3800);
DISPLAY 0.872340 (1798 3800);
PAINT GREEN (1798 3800);
DISPLAY INVISIBLE (1798 3800);
FORCEADD TAP..1
(1800 3750);
FORCEPROP 3 LASTPIN (1750 3750) SIG_NAME P5E_CPU1_PE4_TX_DN<14>
J 0
(1760 3760);
DISPLAY 0.659574 (1760 3760);
PAINT MONO (1760 3760);
DISPLAY INVISIBLE (1760 3760);
FORCEPROP 1 LASTPIN (1750 3750) BN 14
J 0
(1738 3758);
DISPLAY 0.680851 (1738 3758);
PAINT GREEN (1738 3758);
FORCEPROP 2 LAST CDS_LIB standard
J 0
(1800 3750);
DISPLAY INVISIBLE (1800 3750);
FORCEPROP 1 LAST BODY_TYPE PLUMBING
J 0
(1800 3800);
DISPLAY 0.872340 (1800 3800);
PAINT GREEN (1800 3800);
DISPLAY INVISIBLE (1800 3800);
FORCEPROP 1 LAST HDL_TAP TRUE
J 0
(2125 3625);
DISPLAY 0.872340 (2125 3625);
DISPLAY INVISIBLE (2125 3625);
FORCEPROP 1 LAST PATH I145
J 0
(1798 3750);
DISPLAY 0.872340 (1798 3750);
PAINT GREEN (1798 3750);
DISPLAY INVISIBLE (1798 3750);
FORCEADD TAP..1
(1800 3900);
FORCEPROP 3 LASTPIN (1750 3900) SIG_NAME P5E_CPU1_PE4_TX_DP<0>
J 0
(1760 3910);
DISPLAY 0.659574 (1760 3910);
PAINT MONO (1760 3910);
DISPLAY INVISIBLE (1760 3910);
FORCEPROP 1 LASTPIN (1750 3900) BN 0
J 0
(1738 3908);
DISPLAY 0.680851 (1738 3908);
PAINT GREEN (1738 3908);
FORCEPROP 2 LAST CDS_LIB standard
J 0
(1800 3900);
PAINT MONO (1800 3900);
DISPLAY INVISIBLE (1800 3900);
FORCEPROP 1 LAST BODY_TYPE PLUMBING
J 0
(1800 3950);
DISPLAY 0.872340 (1800 3950);
PAINT GREEN (1800 3950);
DISPLAY INVISIBLE (1800 3950);
FORCEPROP 1 LAST HDL_TAP TRUE
J 0
(2125 3775);
DISPLAY 0.872340 (2125 3775);
DISPLAY INVISIBLE (2125 3775);
FORCEPROP 1 LAST PATH I146
J 0
(1798 3900);
DISPLAY 0.872340 (1798 3900);
PAINT GREEN (1798 3900);
DISPLAY INVISIBLE (1798 3900);
FORCEADD TAP..1
(1800 3950);
FORCEPROP 3 LASTPIN (1750 3950) SIG_NAME P5E_CPU1_PE4_TX_DP<1>
J 0
(1760 3960);
DISPLAY 0.659574 (1760 3960);
PAINT MONO (1760 3960);
DISPLAY INVISIBLE (1760 3960);
FORCEPROP 1 LASTPIN (1750 3950) BN 1
J 0
(1738 3958);
DISPLAY 0.680851 (1738 3958);
PAINT GREEN (1738 3958);
FORCEPROP 2 LAST CDS_LIB standard
J 0
(1800 3950);
PAINT MONO (1800 3950);
DISPLAY INVISIBLE (1800 3950);
FORCEPROP 1 LAST BODY_TYPE PLUMBING
J 0
(1800 4000);
DISPLAY 0.872340 (1800 4000);
PAINT GREEN (1800 4000);
DISPLAY INVISIBLE (1800 4000);
FORCEPROP 1 LAST HDL_TAP TRUE
J 0
(2125 3825);
DISPLAY 0.872340 (2125 3825);
DISPLAY INVISIBLE (2125 3825);
FORCEPROP 1 LAST PATH I147
J 0
(1798 3950);
DISPLAY 0.872340 (1798 3950);
PAINT GREEN (1798 3950);
DISPLAY INVISIBLE (1798 3950);
FORCEADD TAP..1
(1800 4050);
FORCEPROP 3 LASTPIN (1750 4050) SIG_NAME P5E_CPU1_PE4_TX_DP<3>
J 0
(1760 4060);
DISPLAY 0.659574 (1760 4060);
PAINT MONO (1760 4060);
DISPLAY INVISIBLE (1760 4060);
FORCEPROP 1 LASTPIN (1750 4050) BN 3
J 0
(1738 4058);
DISPLAY 0.680851 (1738 4058);
PAINT GREEN (1738 4058);
FORCEPROP 2 LAST CDS_LIB standard
J 0
(1800 4050);
PAINT MONO (1800 4050);
DISPLAY INVISIBLE (1800 4050);
FORCEPROP 1 LAST BODY_TYPE PLUMBING
J 0
(1800 4100);
DISPLAY 0.872340 (1800 4100);
PAINT GREEN (1800 4100);
DISPLAY INVISIBLE (1800 4100);
FORCEPROP 1 LAST HDL_TAP TRUE
J 0
(2125 3925);
DISPLAY 0.872340 (2125 3925);
DISPLAY INVISIBLE (2125 3925);
FORCEPROP 1 LAST PATH I148
J 0
(1798 4050);
DISPLAY 0.872340 (1798 4050);
PAINT GREEN (1798 4050);
DISPLAY INVISIBLE (1798 4050);
FORCEADD TAP..1
(1800 4000);
FORCEPROP 3 LASTPIN (1750 4000) SIG_NAME P5E_CPU1_PE4_TX_DP<2>
J 0
(1760 4010);
DISPLAY 0.659574 (1760 4010);
PAINT MONO (1760 4010);
DISPLAY INVISIBLE (1760 4010);
FORCEPROP 1 LASTPIN (1750 4000) BN 2
J 0
(1738 4008);
DISPLAY 0.680851 (1738 4008);
PAINT GREEN (1738 4008);
FORCEPROP 2 LAST CDS_LIB standard
J 0
(1800 4000);
PAINT MONO (1800 4000);
DISPLAY INVISIBLE (1800 4000);
FORCEPROP 1 LAST BODY_TYPE PLUMBING
J 0
(1800 4050);
DISPLAY 0.872340 (1800 4050);
PAINT GREEN (1800 4050);
DISPLAY INVISIBLE (1800 4050);
FORCEPROP 1 LAST HDL_TAP TRUE
J 0
(2125 3875);
DISPLAY 0.872340 (2125 3875);
DISPLAY INVISIBLE (2125 3875);
FORCEPROP 1 LAST PATH I149
J 0
(1798 4000);
DISPLAY 0.872340 (1798 4000);
PAINT GREEN (1798 4000);
DISPLAY INVISIBLE (1798 4000);
FORCEADD TAP..1
(1800 4200);
FORCEPROP 3 LASTPIN (1750 4200) SIG_NAME P5E_CPU1_PE4_TX_DP<6>
J 0
(1760 4210);
DISPLAY 0.659574 (1760 4210);
PAINT MONO (1760 4210);
DISPLAY INVISIBLE (1760 4210);
FORCEPROP 1 LASTPIN (1750 4200) BN 6
J 0
(1738 4208);
DISPLAY 0.680851 (1738 4208);
PAINT GREEN (1738 4208);
FORCEPROP 2 LAST CDS_LIB standard
J 0
(1800 4200);
PAINT MONO (1800 4200);
DISPLAY INVISIBLE (1800 4200);
FORCEPROP 1 LAST BODY_TYPE PLUMBING
J 0
(1800 4250);
DISPLAY 0.872340 (1800 4250);
PAINT GREEN (1800 4250);
DISPLAY INVISIBLE (1800 4250);
FORCEPROP 1 LAST HDL_TAP TRUE
J 0
(2125 4075);
DISPLAY 0.872340 (2125 4075);
DISPLAY INVISIBLE (2125 4075);
FORCEPROP 1 LAST PATH I150
J 0
(1798 4200);
DISPLAY 0.872340 (1798 4200);
PAINT GREEN (1798 4200);
DISPLAY INVISIBLE (1798 4200);
FORCEADD TAP..1
(1800 4150);
FORCEPROP 3 LASTPIN (1750 4150) SIG_NAME P5E_CPU1_PE4_TX_DP<5>
J 0
(1760 4160);
DISPLAY 0.659574 (1760 4160);
PAINT MONO (1760 4160);
DISPLAY INVISIBLE (1760 4160);
FORCEPROP 1 LASTPIN (1750 4150) BN 5
J 0
(1738 4158);
DISPLAY 0.680851 (1738 4158);
PAINT GREEN (1738 4158);
FORCEPROP 2 LAST CDS_LIB standard
J 0
(1800 4150);
PAINT MONO (1800 4150);
DISPLAY INVISIBLE (1800 4150);
FORCEPROP 1 LAST BODY_TYPE PLUMBING
J 0
(1800 4200);
DISPLAY 0.872340 (1800 4200);
PAINT GREEN (1800 4200);
DISPLAY INVISIBLE (1800 4200);
FORCEPROP 1 LAST HDL_TAP TRUE
J 0
(2125 4025);
DISPLAY 0.872340 (2125 4025);
DISPLAY INVISIBLE (2125 4025);
FORCEPROP 1 LAST PATH I151
J 0
(1798 4150);
DISPLAY 0.872340 (1798 4150);
PAINT GREEN (1798 4150);
DISPLAY INVISIBLE (1798 4150);
FORCEADD TAP..1
(1800 4100);
FORCEPROP 3 LASTPIN (1750 4100) SIG_NAME P5E_CPU1_PE4_TX_DP<4>
J 0
(1760 4110);
DISPLAY 0.659574 (1760 4110);
PAINT MONO (1760 4110);
DISPLAY INVISIBLE (1760 4110);
FORCEPROP 1 LASTPIN (1750 4100) BN 4
J 0
(1738 4108);
DISPLAY 0.680851 (1738 4108);
PAINT GREEN (1738 4108);
FORCEPROP 2 LAST CDS_LIB standard
J 0
(1800 4100);
PAINT MONO (1800 4100);
DISPLAY INVISIBLE (1800 4100);
FORCEPROP 1 LAST BODY_TYPE PLUMBING
J 0
(1800 4150);
DISPLAY 0.872340 (1800 4150);
PAINT GREEN (1800 4150);
DISPLAY INVISIBLE (1800 4150);
FORCEPROP 1 LAST HDL_TAP TRUE
J 0
(2125 3975);
DISPLAY 0.872340 (2125 3975);
DISPLAY INVISIBLE (2125 3975);
FORCEPROP 1 LAST PATH I152
J 0
(1798 4100);
DISPLAY 0.872340 (1798 4100);
PAINT GREEN (1798 4100);
DISPLAY INVISIBLE (1798 4100);
FORCEADD TAP..1
(1800 4250);
FORCEPROP 3 LASTPIN (1750 4250) SIG_NAME P5E_CPU1_PE4_TX_DP<7>
J 0
(1760 4260);
DISPLAY 0.659574 (1760 4260);
PAINT MONO (1760 4260);
DISPLAY INVISIBLE (1760 4260);
FORCEPROP 1 LASTPIN (1750 4250) BN 7
J 0
(1738 4258);
DISPLAY 0.680851 (1738 4258);
PAINT GREEN (1738 4258);
FORCEPROP 2 LAST CDS_LIB standard
J 0
(1800 4250);
PAINT MONO (1800 4250);
DISPLAY INVISIBLE (1800 4250);
FORCEPROP 1 LAST BODY_TYPE PLUMBING
J 0
(1800 4300);
DISPLAY 0.872340 (1800 4300);
PAINT GREEN (1800 4300);
DISPLAY INVISIBLE (1800 4300);
FORCEPROP 1 LAST HDL_TAP TRUE
J 0
(2125 4125);
DISPLAY 0.872340 (2125 4125);
DISPLAY INVISIBLE (2125 4125);
FORCEPROP 1 LAST PATH I153
J 0
(1798 4250);
DISPLAY 0.872340 (1798 4250);
PAINT GREEN (1798 4250);
DISPLAY INVISIBLE (1798 4250);
FORCEADD TAP..1
(1800 4300);
FORCEPROP 3 LASTPIN (1750 4300) SIG_NAME P5E_CPU1_PE4_TX_DP<8>
J 0
(1760 4310);
DISPLAY 0.659574 (1760 4310);
PAINT MONO (1760 4310);
DISPLAY INVISIBLE (1760 4310);
FORCEPROP 1 LASTPIN (1750 4300) BN 8
J 0
(1738 4308);
DISPLAY 0.680851 (1738 4308);
PAINT GREEN (1738 4308);
FORCEPROP 2 LAST CDS_LIB standard
J 0
(1800 4300);
PAINT MONO (1800 4300);
DISPLAY INVISIBLE (1800 4300);
FORCEPROP 1 LAST BODY_TYPE PLUMBING
J 0
(1800 4350);
DISPLAY 0.872340 (1800 4350);
PAINT GREEN (1800 4350);
DISPLAY INVISIBLE (1800 4350);
FORCEPROP 1 LAST HDL_TAP TRUE
J 0
(2125 4175);
DISPLAY 0.872340 (2125 4175);
DISPLAY INVISIBLE (2125 4175);
FORCEPROP 1 LAST PATH I154
J 0
(1798 4300);
DISPLAY 0.872340 (1798 4300);
PAINT GREEN (1798 4300);
DISPLAY INVISIBLE (1798 4300);
FORCEADD TAP..1
(1800 4450);
FORCEPROP 3 LASTPIN (1750 4450) SIG_NAME P5E_CPU1_PE4_TX_DP<11>
J 0
(1760 4460);
DISPLAY 0.659574 (1760 4460);
PAINT MONO (1760 4460);
DISPLAY INVISIBLE (1760 4460);
FORCEPROP 1 LASTPIN (1750 4450) BN 11
J 0
(1738 4458);
DISPLAY 0.680851 (1738 4458);
PAINT GREEN (1738 4458);
FORCEPROP 2 LAST CDS_LIB standard
J 0
(1800 4450);
DISPLAY INVISIBLE (1800 4450);
FORCEPROP 1 LAST BODY_TYPE PLUMBING
J 0
(1800 4500);
DISPLAY 0.872340 (1800 4500);
PAINT GREEN (1800 4500);
DISPLAY INVISIBLE (1800 4500);
FORCEPROP 1 LAST HDL_TAP TRUE
J 0
(2125 4325);
DISPLAY 0.872340 (2125 4325);
DISPLAY INVISIBLE (2125 4325);
FORCEPROP 1 LAST PATH I155
J 0
(1798 4450);
DISPLAY 0.872340 (1798 4450);
PAINT GREEN (1798 4450);
DISPLAY INVISIBLE (1798 4450);
FORCEADD TAP..1
(1800 4400);
FORCEPROP 3 LASTPIN (1750 4400) SIG_NAME P5E_CPU1_PE4_TX_DP<10>
J 0
(1760 4410);
DISPLAY 0.659574 (1760 4410);
PAINT MONO (1760 4410);
DISPLAY INVISIBLE (1760 4410);
FORCEPROP 1 LASTPIN (1750 4400) BN 10
J 0
(1738 4408);
DISPLAY 0.680851 (1738 4408);
PAINT GREEN (1738 4408);
FORCEPROP 2 LAST CDS_LIB standard
J 0
(1800 4400);
DISPLAY INVISIBLE (1800 4400);
FORCEPROP 1 LAST BODY_TYPE PLUMBING
J 0
(1800 4450);
DISPLAY 0.872340 (1800 4450);
PAINT GREEN (1800 4450);
DISPLAY INVISIBLE (1800 4450);
FORCEPROP 1 LAST HDL_TAP TRUE
J 0
(2125 4275);
DISPLAY 0.872340 (2125 4275);
DISPLAY INVISIBLE (2125 4275);
FORCEPROP 1 LAST PATH I156
J 0
(1798 4400);
DISPLAY 0.872340 (1798 4400);
PAINT GREEN (1798 4400);
DISPLAY INVISIBLE (1798 4400);
FORCEADD TAP..1
(1800 4350);
FORCEPROP 3 LASTPIN (1750 4350) SIG_NAME P5E_CPU1_PE4_TX_DP<9>
J 0
(1760 4360);
DISPLAY 0.659574 (1760 4360);
PAINT MONO (1760 4360);
DISPLAY INVISIBLE (1760 4360);
FORCEPROP 1 LASTPIN (1750 4350) BN 9
J 0
(1738 4358);
DISPLAY 0.680851 (1738 4358);
PAINT GREEN (1738 4358);
FORCEPROP 2 LAST CDS_LIB standard
J 0
(1800 4350);
DISPLAY INVISIBLE (1800 4350);
FORCEPROP 1 LAST BODY_TYPE PLUMBING
J 0
(1800 4400);
DISPLAY 0.872340 (1800 4400);
PAINT GREEN (1800 4400);
DISPLAY INVISIBLE (1800 4400);
FORCEPROP 1 LAST HDL_TAP TRUE
J 0
(2125 4225);
DISPLAY 0.872340 (2125 4225);
DISPLAY INVISIBLE (2125 4225);
FORCEPROP 1 LAST PATH I157
J 0
(1798 4350);
DISPLAY 0.872340 (1798 4350);
PAINT GREEN (1798 4350);
DISPLAY INVISIBLE (1798 4350);
FORCEADD TAP..1
(1800 4550);
FORCEPROP 3 LASTPIN (1750 4550) SIG_NAME P5E_CPU1_PE4_TX_DP<13>
J 0
(1760 4560);
DISPLAY 0.659574 (1760 4560);
PAINT MONO (1760 4560);
DISPLAY INVISIBLE (1760 4560);
FORCEPROP 1 LASTPIN (1750 4550) BN 13
J 0
(1738 4558);
DISPLAY 0.680851 (1738 4558);
PAINT GREEN (1738 4558);
FORCEPROP 2 LAST CDS_LIB standard
J 0
(1800 4550);
DISPLAY INVISIBLE (1800 4550);
FORCEPROP 1 LAST BODY_TYPE PLUMBING
J 0
(1800 4600);
DISPLAY 0.872340 (1800 4600);
PAINT GREEN (1800 4600);
DISPLAY INVISIBLE (1800 4600);
FORCEPROP 1 LAST HDL_TAP TRUE
J 0
(2125 4425);
DISPLAY 0.872340 (2125 4425);
DISPLAY INVISIBLE (2125 4425);
FORCEPROP 1 LAST PATH I158
J 0
(1798 4550);
DISPLAY 0.872340 (1798 4550);
PAINT GREEN (1798 4550);
DISPLAY INVISIBLE (1798 4550);
FORCEADD TAP..1
(1800 4500);
FORCEPROP 3 LASTPIN (1750 4500) SIG_NAME P5E_CPU1_PE4_TX_DP<12>
J 0
(1760 4510);
DISPLAY 0.659574 (1760 4510);
PAINT MONO (1760 4510);
DISPLAY INVISIBLE (1760 4510);
FORCEPROP 1 LASTPIN (1750 4500) BN 12
J 0
(1738 4508);
DISPLAY 0.680851 (1738 4508);
PAINT GREEN (1738 4508);
FORCEPROP 2 LAST CDS_LIB standard
J 0
(1800 4500);
DISPLAY INVISIBLE (1800 4500);
FORCEPROP 1 LAST BODY_TYPE PLUMBING
J 0
(1800 4550);
DISPLAY 0.872340 (1800 4550);
PAINT GREEN (1800 4550);
DISPLAY INVISIBLE (1800 4550);
FORCEPROP 1 LAST HDL_TAP TRUE
J 0
(2125 4375);
DISPLAY 0.872340 (2125 4375);
DISPLAY INVISIBLE (2125 4375);
FORCEPROP 1 LAST PATH I159
J 0
(1798 4500);
DISPLAY 0.872340 (1798 4500);
PAINT GREEN (1798 4500);
DISPLAY INVISIBLE (1798 4500);
FORCEADD TAP..1
(1800 4600);
FORCEPROP 3 LASTPIN (1750 4600) SIG_NAME P5E_CPU1_PE4_TX_DP<14>
J 0
(1760 4610);
DISPLAY 0.659574 (1760 4610);
PAINT MONO (1760 4610);
DISPLAY INVISIBLE (1760 4610);
FORCEPROP 1 LASTPIN (1750 4600) BN 14
J 0
(1738 4608);
DISPLAY 0.680851 (1738 4608);
PAINT GREEN (1738 4608);
FORCEPROP 2 LAST CDS_LIB standard
J 0
(1800 4600);
DISPLAY INVISIBLE (1800 4600);
FORCEPROP 1 LAST BODY_TYPE PLUMBING
J 0
(1800 4650);
DISPLAY 0.872340 (1800 4650);
PAINT GREEN (1800 4650);
DISPLAY INVISIBLE (1800 4650);
FORCEPROP 1 LAST HDL_TAP TRUE
J 0
(2125 4475);
DISPLAY 0.872340 (2125 4475);
DISPLAY INVISIBLE (2125 4475);
FORCEPROP 1 LAST PATH I160
J 0
(1798 4600);
DISPLAY 0.872340 (1798 4600);
PAINT GREEN (1798 4600);
DISPLAY INVISIBLE (1798 4600);
FORCEADD TAP..1
(1800 4650);
FORCEPROP 3 LASTPIN (1750 4650) SIG_NAME P5E_CPU1_PE4_TX_DP<15>
J 0
(1760 4660);
DISPLAY 0.659574 (1760 4660);
PAINT MONO (1760 4660);
DISPLAY INVISIBLE (1760 4660);
FORCEPROP 1 LASTPIN (1750 4650) BN 15
J 0
(1738 4658);
DISPLAY 0.680851 (1738 4658);
PAINT GREEN (1738 4658);
FORCEPROP 2 LAST CDS_LIB standard
J 0
(1800 4650);
DISPLAY INVISIBLE (1800 4650);
FORCEPROP 1 LAST BODY_TYPE PLUMBING
J 0
(1800 4700);
DISPLAY 0.872340 (1800 4700);
PAINT GREEN (1800 4700);
DISPLAY INVISIBLE (1800 4700);
FORCEPROP 1 LAST HDL_TAP TRUE
J 0
(2125 4525);
DISPLAY 0.872340 (2125 4525);
DISPLAY INVISIBLE (2125 4525);
FORCEPROP 1 LAST PATH I161
J 0
(1798 4650);
DISPLAY 0.872340 (1798 4650);
PAINT GREEN (1798 4650);
DISPLAY INVISIBLE (1798 4650);
FORCEADD OFFPAGE..2
(2900 3825);
FORCEPROP 2 LAST $XR0 177 
J 0
(3089 3825);
DISPLAY 0.638298 (3089 3825);
PAINT MONO (3089 3825);
FORCEPROP 2 LAST CDS_LIB standard
J 0
(2900 3825);
PAINT MONO (2900 3825);
DISPLAY INVISIBLE (2900 3825);
FORCEPROP 1 LAST OFFPAGE TRUE
J 0
(3225 3700);
DISPLAY 1.170213 (3225 3700);
PAINT GREEN (3225 3700);
DISPLAY INVISIBLE (3225 3700);
FORCEPROP 1 LAST COMMENT_BODY TRUE
J 0
(2855 3730);
DISPLAY 1.170213 (2855 3730);
PAINT GREEN (2855 3730);
DISPLAY INVISIBLE (2855 3730);
FORCEPROP 2 LAST PATH I162
J 0
(3100 3875);
DISPLAY 1.021277 (3100 3875);
DISPLAY INVISIBLE (3100 3875);
FORCEADD OFFPAGE..2
(2900 4675);
FORCEPROP 2 LAST $XR0 177 
J 0
(3089 4675);
DISPLAY 0.638298 (3089 4675);
PAINT MONO (3089 4675);
FORCEPROP 2 LAST CDS_LIB standard
J 0
(2900 4675);
PAINT MONO (2900 4675);
DISPLAY INVISIBLE (2900 4675);
FORCEPROP 1 LAST OFFPAGE TRUE
J 0
(3225 4550);
DISPLAY 1.170213 (3225 4550);
PAINT GREEN (3225 4550);
DISPLAY INVISIBLE (3225 4550);
FORCEPROP 1 LAST COMMENT_BODY TRUE
J 0
(2855 4580);
DISPLAY 1.170213 (2855 4580);
PAINT GREEN (2855 4580);
DISPLAY INVISIBLE (2855 4580);
FORCEPROP 2 LAST PATH I163
J 0
(3100 4725);
DISPLAY 1.021277 (3100 4725);
DISPLAY INVISIBLE (3100 4725);
FORCEADD SOCKET4677_AZIF0045P001C01CS..21
(125 3850);
FORCEPROP 1 LAST PART_NUMBER DGA^7000023
J 0
(-925 4900);
DISPLAY 0.723404 (-925 4900);
PAINT GREEN (-925 4900);
DISPLAY INVISIBLE (-925 4900);
FORCEPROP 2 LAST VALUE SOCKET4677_AZIF0045-P001C01CS
J 0
(-925 5025);
DISPLAY 1.021277 (-925 5025);
FORCEPROP 1 LAST MATERIAL IO
J 0
(-925 4825);
DISPLAY 0.723404 (-925 4825);
PAINT GREEN (-925 4825);
FORCEPROP 2 LAST PART_TYPE SMLF
J 0
(-925 5075);
DISPLAY 1.021277 (-925 5075);
FORCEPROP 1 LAST $LOCATION U1
J 0
(-925 4975);
DISPLAY 0.723404 (-925 4975);
PAINT GREEN (-925 4975);
FORCEPROP 0 LASTPIN (-1075 3050) $PN J90
J 2
(-1085 3060);
DISPLAY 0.680851 (-1085 3060);
PAINT MONO (-1085 3060);
FORCEPROP 0 LASTPIN (-1075 3100) $PN P89
J 2
(-1085 3110);
DISPLAY 0.680851 (-1085 3110);
PAINT MONO (-1085 3110);
FORCEPROP 0 LASTPIN (-1075 3150) $PN T91
J 2
(-1085 3160);
DISPLAY 0.680851 (-1085 3160);
PAINT MONO (-1085 3160);
FORCEPROP 0 LASTPIN (-1075 3200) $PN V89
J 2
(-1085 3210);
DISPLAY 0.680851 (-1085 3210);
PAINT MONO (-1085 3210);
FORCEPROP 0 LASTPIN (-1075 3250) $PN Y91
J 2
(-1085 3260);
DISPLAY 0.680851 (-1085 3260);
PAINT MONO (-1085 3260);
FORCEPROP 0 LASTPIN (-1075 3300) $PN AB89
J 2
(-1085 3310);
DISPLAY 0.680851 (-1085 3310);
PAINT MONO (-1085 3310);
FORCEPROP 0 LASTPIN (-1075 3350) $PN AD91
J 2
(-1085 3360);
DISPLAY 0.680851 (-1085 3360);
PAINT MONO (-1085 3360);
FORCEPROP 0 LASTPIN (-1075 3400) $PN AF89
J 2
(-1085 3410);
DISPLAY 0.680851 (-1085 3410);
PAINT MONO (-1085 3410);
FORCEPROP 0 LASTPIN (-1075 3450) $PN AH91
J 2
(-1085 3460);
DISPLAY 0.680851 (-1085 3460);
PAINT MONO (-1085 3460);
FORCEPROP 0 LASTPIN (-1075 3500) $PN AK89
J 2
(-1085 3510);
DISPLAY 0.680851 (-1085 3510);
PAINT MONO (-1085 3510);
FORCEPROP 0 LASTPIN (-1075 3550) $PN AM91
J 2
(-1085 3560);
DISPLAY 0.680851 (-1085 3560);
PAINT MONO (-1085 3560);
FORCEPROP 0 LASTPIN (-1075 3600) $PN AP89
J 2
(-1085 3610);
DISPLAY 0.680851 (-1085 3610);
PAINT MONO (-1085 3610);
FORCEPROP 0 LASTPIN (-1075 3650) $PN AT91
J 2
(-1085 3660);
DISPLAY 0.680851 (-1085 3660);
PAINT MONO (-1085 3660);
FORCEPROP 0 LASTPIN (-1075 3700) $PN AV89
J 2
(-1085 3710);
DISPLAY 0.680851 (-1085 3710);
PAINT MONO (-1085 3710);
FORCEPROP 0 LASTPIN (-1075 3750) $PN AY91
J 2
(-1085 3760);
DISPLAY 0.680851 (-1085 3760);
PAINT MONO (-1085 3760);
FORCEPROP 0 LASTPIN (-1075 3800) $PN BB89
J 2
(-1085 3810);
DISPLAY 0.680851 (-1085 3810);
PAINT MONO (-1085 3810);
FORCEPROP 0 LASTPIN (-1075 3900) $PN K89
J 2
(-1085 3910);
DISPLAY 0.680851 (-1085 3910);
PAINT MONO (-1085 3910);
FORCEPROP 0 LASTPIN (-1075 3950) $PN N90
J 2
(-1085 3960);
DISPLAY 0.680851 (-1085 3960);
PAINT MONO (-1085 3960);
FORCEPROP 0 LASTPIN (-1075 4000) $PN R90
J 2
(-1085 4010);
DISPLAY 0.680851 (-1085 4010);
PAINT MONO (-1085 4010);
FORCEPROP 0 LASTPIN (-1075 4050) $PN U90
J 2
(-1085 4060);
DISPLAY 0.680851 (-1085 4060);
PAINT MONO (-1085 4060);
FORCEPROP 0 LASTPIN (-1075 4100) $PN W90
J 2
(-1085 4110);
DISPLAY 0.680851 (-1085 4110);
PAINT MONO (-1085 4110);
FORCEPROP 0 LASTPIN (-1075 4150) $PN AA90
J 2
(-1085 4160);
DISPLAY 0.680851 (-1085 4160);
PAINT MONO (-1085 4160);
FORCEPROP 0 LASTPIN (-1075 4200) $PN AC90
J 2
(-1085 4210);
DISPLAY 0.680851 (-1085 4210);
PAINT MONO (-1085 4210);
FORCEPROP 0 LASTPIN (-1075 4250) $PN AE90
J 2
(-1085 4260);
DISPLAY 0.680851 (-1085 4260);
PAINT MONO (-1085 4260);
FORCEPROP 0 LASTPIN (-1075 4300) $PN AG90
J 2
(-1085 4310);
DISPLAY 0.680851 (-1085 4310);
PAINT MONO (-1085 4310);
FORCEPROP 0 LASTPIN (-1075 4350) $PN AJ90
J 2
(-1085 4360);
DISPLAY 0.680851 (-1085 4360);
PAINT MONO (-1085 4360);
FORCEPROP 0 LASTPIN (-1075 4400) $PN AL90
J 2
(-1085 4410);
DISPLAY 0.680851 (-1085 4410);
PAINT MONO (-1085 4410);
FORCEPROP 0 LASTPIN (-1075 4450) $PN AN90
J 2
(-1085 4460);
DISPLAY 0.680851 (-1085 4460);
PAINT MONO (-1085 4460);
FORCEPROP 0 LASTPIN (-1075 4500) $PN AR90
J 2
(-1085 4510);
DISPLAY 0.680851 (-1085 4510);
PAINT MONO (-1085 4510);
FORCEPROP 0 LASTPIN (-1075 4550) $PN AU90
J 2
(-1085 4560);
DISPLAY 0.680851 (-1085 4560);
PAINT MONO (-1085 4560);
FORCEPROP 0 LASTPIN (-1075 4600) $PN AW90
J 2
(-1085 4610);
DISPLAY 0.680851 (-1085 4610);
PAINT MONO (-1085 4610);
FORCEPROP 0 LASTPIN (-1075 4650) $PN BA90
J 2
(-1085 4660);
DISPLAY 0.680851 (-1085 4660);
PAINT MONO (-1085 4660);
FORCEPROP 0 LASTPIN (1325 3050) $PN L86
J 0
(1335 3060);
DISPLAY 0.680851 (1335 3060);
PAINT MONO (1335 3060);
FORCEPROP 0 LASTPIN (1325 3100) $PN P85
J 0
(1335 3110);
DISPLAY 0.680851 (1335 3110);
PAINT MONO (1335 3110);
FORCEPROP 0 LASTPIN (1325 3150) $PN R86
J 0
(1335 3160);
DISPLAY 0.680851 (1335 3160);
PAINT MONO (1335 3160);
FORCEPROP 0 LASTPIN (1325 3200) $PN U86
J 0
(1335 3210);
DISPLAY 0.680851 (1335 3210);
PAINT MONO (1335 3210);
FORCEPROP 0 LASTPIN (1325 3250) $PN W86
J 0
(1335 3260);
DISPLAY 0.680851 (1335 3260);
PAINT MONO (1335 3260);
FORCEPROP 0 LASTPIN (1325 3300) $PN AA86
J 0
(1335 3310);
DISPLAY 0.680851 (1335 3310);
PAINT MONO (1335 3310);
FORCEPROP 0 LASTPIN (1325 3350) $PN AC86
J 0
(1335 3360);
DISPLAY 0.680851 (1335 3360);
PAINT MONO (1335 3360);
FORCEPROP 0 LASTPIN (1325 3400) $PN AE86
J 0
(1335 3410);
DISPLAY 0.680851 (1335 3410);
PAINT MONO (1335 3410);
FORCEPROP 0 LASTPIN (1325 3450) $PN AG86
J 0
(1335 3460);
DISPLAY 0.680851 (1335 3460);
PAINT MONO (1335 3460);
FORCEPROP 0 LASTPIN (1325 3500) $PN AJ86
J 0
(1335 3510);
DISPLAY 0.680851 (1335 3510);
PAINT MONO (1335 3510);
FORCEPROP 0 LASTPIN (1325 3550) $PN AL86
J 0
(1335 3560);
DISPLAY 0.680851 (1335 3560);
PAINT MONO (1335 3560);
FORCEPROP 0 LASTPIN (1325 3600) $PN AP85
J 0
(1335 3610);
DISPLAY 0.680851 (1335 3610);
PAINT MONO (1335 3610);
FORCEPROP 0 LASTPIN (1325 3650) $PN AR86
J 0
(1335 3660);
DISPLAY 0.680851 (1335 3660);
PAINT MONO (1335 3660);
FORCEPROP 0 LASTPIN (1325 3700) $PN AU86
J 0
(1335 3710);
DISPLAY 0.680851 (1335 3710);
PAINT MONO (1335 3710);
FORCEPROP 0 LASTPIN (1325 3750) $PN AW86
J 0
(1335 3760);
DISPLAY 0.680851 (1335 3760);
PAINT MONO (1335 3760);
FORCEPROP 0 LASTPIN (1325 3800) $PN BA86
J 0
(1335 3810);
DISPLAY 0.680851 (1335 3810);
PAINT MONO (1335 3810);
FORCEPROP 0 LASTPIN (1325 3900) $PN M87
J 0
(1335 3910);
DISPLAY 0.680851 (1335 3910);
PAINT MONO (1335 3910);
FORCEPROP 0 LASTPIN (1325 3950) $PN N86
J 0
(1335 3960);
DISPLAY 0.680851 (1335 3960);
PAINT MONO (1335 3960);
FORCEPROP 0 LASTPIN (1325 4000) $PN T87
J 0
(1335 4010);
DISPLAY 0.680851 (1335 4010);
PAINT MONO (1335 4010);
FORCEPROP 0 LASTPIN (1325 4050) $PN V85
J 0
(1335 4060);
DISPLAY 0.680851 (1335 4060);
PAINT MONO (1335 4060);
FORCEPROP 0 LASTPIN (1325 4100) $PN Y87
J 0
(1335 4110);
DISPLAY 0.680851 (1335 4110);
PAINT MONO (1335 4110);
FORCEPROP 0 LASTPIN (1325 4150) $PN AB85
J 0
(1335 4160);
DISPLAY 0.680851 (1335 4160);
PAINT MONO (1335 4160);
FORCEPROP 0 LASTPIN (1325 4200) $PN AD87
J 0
(1335 4210);
DISPLAY 0.680851 (1335 4210);
PAINT MONO (1335 4210);
FORCEPROP 0 LASTPIN (1325 4250) $PN AF85
J 0
(1335 4260);
DISPLAY 0.680851 (1335 4260);
PAINT MONO (1335 4260);
FORCEPROP 0 LASTPIN (1325 4300) $PN AH87
J 0
(1335 4310);
DISPLAY 0.680851 (1335 4310);
PAINT MONO (1335 4310);
FORCEPROP 0 LASTPIN (1325 4350) $PN AK85
J 0
(1335 4360);
DISPLAY 0.680851 (1335 4360);
PAINT MONO (1335 4360);
FORCEPROP 0 LASTPIN (1325 4400) $PN AM87
J 0
(1335 4410);
DISPLAY 0.680851 (1335 4410);
PAINT MONO (1335 4410);
FORCEPROP 0 LASTPIN (1325 4450) $PN AN86
J 0
(1335 4460);
DISPLAY 0.680851 (1335 4460);
PAINT MONO (1335 4460);
FORCEPROP 0 LASTPIN (1325 4500) $PN AT87
J 0
(1335 4510);
DISPLAY 0.680851 (1335 4510);
PAINT MONO (1335 4510);
FORCEPROP 0 LASTPIN (1325 4550) $PN AV85
J 0
(1335 4560);
DISPLAY 0.680851 (1335 4560);
PAINT MONO (1335 4560);
FORCEPROP 0 LASTPIN (1325 4600) $PN AY87
J 0
(1335 4610);
DISPLAY 0.680851 (1335 4610);
PAINT MONO (1335 4610);
FORCEPROP 0 LASTPIN (1325 4650) $PN BB85
J 0
(1335 4660);
DISPLAY 0.680851 (1335 4660);
PAINT MONO (1335 4660);
FORCEPROP 1 LAST CDS_LMAN_SYM_OUTLINE -1050,950,1050,-950
J 0
(125 3850);
DISPLAY 0.468085 (125 3850);
PAINT GREEN (125 3850);
DISPLAY INVISIBLE (125 3850);
FORCEPROP 1 LAST NEEDS_NO_SIZE TRUE
J 0
(125 3850);
DISPLAY 0.723404 (125 3850);
PAINT GREEN (125 3850);
DISPLAY INVISIBLE (125 3850);
FORCEPROP 2 LAST CDS_LIB pure_quanta
J 0
(125 3850);
DISPLAY INVISIBLE (125 3850);
FORCEPROP 2 LAST CDS_LOCATION U1
J 0
(-925 5125);
DISPLAY 1.021277 (-925 5125);
DISPLAY INVISIBLE (-925 5125);
FORCEPROP 0 LAST $SEC 21
J 0
(-925 5125);
DISPLAY 0.680851 (-925 5125);
PAINT MONO (-925 5125);
DISPLAY INVISIBLE (-925 5125);
FORCEPROP 2 LAST CDS_SEC 21
J 0
(-925 5125);
DISPLAY 1.021277 (-925 5125);
DISPLAY INVISIBLE (-925 5125);
FORCEPROP 1 LAST PATH I18
J 0
(125 3850);
DISPLAY 0.723404 (125 3850);
PAINT GREEN (125 3850);
DISPLAY INVISIBLE (125 3850);
FORCEADD OFFPAGE..1
(-2800 3825);
FORCEPROP 2 LAST $XR1 143 
J 0
(-3172 3825);
DISPLAY 0.638298 (-3172 3825);
PAINT MONO (-3172 3825);
FORCEPROP 2 LAST $XR0 142 
J 0
(-3052 3825);
DISPLAY 0.638298 (-3052 3825);
PAINT MONO (-3052 3825);
FORCEPROP 2 LAST CDS_LIB standard
J 0
(-2800 3825);
PAINT MONO (-2800 3825);
DISPLAY INVISIBLE (-2800 3825);
FORCEPROP 1 LAST OFFPAGE TRUE
J 0
(-2475 3700);
DISPLAY 0.872340 (-2475 3700);
DISPLAY INVISIBLE (-2475 3700);
FORCEPROP 1 LAST COMMENT_BODY TRUE
J 0
(-2675 3725);
DISPLAY 0.872340 (-2675 3725);
PAINT GREEN (-2675 3725);
DISPLAY INVISIBLE (-2675 3725);
FORCEPROP 2 LAST PATH I96
J 0
(-3050 3875);
DISPLAY 1.021277 (-3050 3875);
DISPLAY INVISIBLE (-3050 3875);
FORCEADD OFFPAGE..1
(-2800 4675);
FORCEPROP 2 LAST $XR1 143 
J 0
(-3172 4675);
DISPLAY 0.638298 (-3172 4675);
PAINT MONO (-3172 4675);
FORCEPROP 2 LAST $XR0 142 
J 0
(-3052 4675);
DISPLAY 0.638298 (-3052 4675);
PAINT MONO (-3052 4675);
FORCEPROP 2 LAST CDS_LIB standard
J 0
(-2800 4675);
PAINT MONO (-2800 4675);
DISPLAY INVISIBLE (-2800 4675);
FORCEPROP 1 LAST OFFPAGE TRUE
J 0
(-2475 4550);
DISPLAY 0.872340 (-2475 4550);
DISPLAY INVISIBLE (-2475 4550);
FORCEPROP 1 LAST COMMENT_BODY TRUE
J 0
(-2675 4575);
DISPLAY 0.872340 (-2675 4575);
PAINT GREEN (-2675 4575);
DISPLAY INVISIBLE (-2675 4575);
FORCEPROP 2 LAST PATH I97
J 0
(-3050 4725);
DISPLAY 1.021277 (-3050 4725);
DISPLAY INVISIBLE (-3050 4725);
FORCEADD TAP..1
R 2
(-1550 3050);
FORCEPROP 3 LASTPIN (-1500 3050) SIG_NAME P5E_CPU1_PE4_RX_DN<0>
J 0
(-1490 3060);
DISPLAY 0.659574 (-1490 3060);
PAINT MONO (-1490 3060);
DISPLAY INVISIBLE (-1490 3060);
FORCEPROP 1 LASTPIN (-1500 3050) BN 0
J 2
(-1488 3058);
DISPLAY 0.680851 (-1488 3058);
PAINT GREEN (-1488 3058);
FORCEPROP 2 LAST CDS_LIB standard
J 0
(-1550 3050);
DISPLAY INVISIBLE (-1550 3050);
FORCEPROP 1 LAST BODY_TYPE PLUMBING
J 2
(-1550 3100);
DISPLAY 0.872340 (-1550 3100);
PAINT GREEN (-1550 3100);
DISPLAY INVISIBLE (-1550 3100);
FORCEPROP 1 LAST HDL_TAP TRUE
J 2
(-1875 2925);
DISPLAY 0.872340 (-1875 2925);
DISPLAY INVISIBLE (-1875 2925);
FORCEPROP 1 LAST PATH I98
J 2
(-1548 3050);
DISPLAY 0.872340 (-1548 3050);
PAINT GREEN (-1548 3050);
DISPLAY INVISIBLE (-1548 3050);
FORCEADD TAP..1
R 2
(-1550 3100);
FORCEPROP 3 LASTPIN (-1500 3100) SIG_NAME P5E_CPU1_PE4_RX_DN<1>
J 0
(-1490 3110);
DISPLAY 0.659574 (-1490 3110);
PAINT MONO (-1490 3110);
DISPLAY INVISIBLE (-1490 3110);
FORCEPROP 1 LASTPIN (-1500 3100) BN 1
J 2
(-1488 3108);
DISPLAY 0.680851 (-1488 3108);
PAINT GREEN (-1488 3108);
FORCEPROP 2 LAST CDS_LIB standard
J 0
(-1550 3100);
DISPLAY INVISIBLE (-1550 3100);
FORCEPROP 1 LAST BODY_TYPE PLUMBING
J 2
(-1550 3150);
DISPLAY 0.872340 (-1550 3150);
PAINT GREEN (-1550 3150);
DISPLAY INVISIBLE (-1550 3150);
FORCEPROP 1 LAST HDL_TAP TRUE
J 2
(-1875 2975);
DISPLAY 0.872340 (-1875 2975);
DISPLAY INVISIBLE (-1875 2975);
FORCEPROP 1 LAST PATH I99
J 2
(-1548 3100);
DISPLAY 0.872340 (-1548 3100);
PAINT GREEN (-1548 3100);
DISPLAY INVISIBLE (-1548 3100);
FORCEADD QUANTA_TITLE_BLOCK_C..1
(4725 -850);
FORCEPROP 0 LAST CDS_CON_LAST_MODIFIED Fri Aug 25 14:00:44 2023
J 0
(2840 -835);
PAINT MONO (2840 -835);
DISPLAY INVISIBLE (2840 -835);
FORCEPROP 1 LAST CUSTOM_TXT_CDS <CON_LAST_MODIFIED>
J 0
(2840 -835);
DISPLAY 0.978723 (2840 -835);
FORCEPROP 2 LAST CUSTOM_TXT_CDS <XR_PAGE_TITLE>
J 0
(-3165 4400);
DISPLAY 0.638298 (-3165 4400);
PAINT PINK (-3165 4400);
DISPLAY INVISIBLE (-3165 4400);
FORCEPROP 2 LAST CUSTOM_TXT_CDS <Q_NUMBER>
J 0
(3322 -747);
DISPLAY 1.212766 (3322 -747);
FORCEPROP 1 LAST CUSTOM_TXT_CDS <NAME_2>
J 0
(1550 -800);
FORCEPROP 1 LAST CUSTOM_TXT_CDS <NAME_1>
J 0
(1550 -675);
FORCEPROP 1 LAST CUSTOM_TXT_CDS <Q_PROJ>
J 0
(2343 -748);
DISPLAY 1.212766 (2343 -748);
FORCEPROP 1 LAST CUSTOM_TXT_CDS <Q_REV>
J 0
(4541 -747);
DISPLAY 1.212766 (4541 -747);
FORCEPROP 1 LAST CUSTOM_TXT_CDS <CON_PAGE_NUM> OF <CON_TOTAL_PAGES>
J 0
(4279 -832);
DISPLAY 0.978723 (4279 -832);
FORCEPROP 1 LAST Q_TITLE SPR CPU1 - PCIE PE4 (19 OF 30)
J 0
(-4641 -824);
DISPLAY 1.957447 (-4641 -824);
PAINT GREEN (-4641 -824);
FORCEPROP 1 LAST Q_DEPT 
J 1
(962 -801);
DISPLAY 1.957447 (962 -801);
PAINT GREEN (962 -801);
FORCEPROP 1 LAST COMMENT_BODY TRUE
J 0
(4737 -863);
DISPLAY 0.978723 (4737 -863);
PAINT GREEN (4737 -863);
DISPLAY INVISIBLE (4737 -863);
FORCEPROP 2 LAST CDS_XR_PAGE_TITLE CR-62 : @S9S_MB_2U_LIB.S9S_MB_2U(SCH_1):PAGE62
J 0
(-3165 4400);
DISPLAY 0.638298 (-3165 4400);
PAINT PINK (-3165 4400);
DISPLAY INVISIBLE (-3165 4400);
FORCEPROP 2 LAST PAGE_BORDER TRUE
J 0
(-3165 4400);
DISPLAY 0.638298 (-3165 4400);
PAINT PINK (-3165 4400);
DISPLAY INVISIBLE (-3165 4400);
FORCEPROP 1 LAST CDS_LMAN_SYM_OUTLINE -9475,6775,100,-125
J 0
(4725 -850);
DISPLAY 0.468085 (4725 -850);
PAINT GREEN (4725 -850);
DISPLAY INVISIBLE (4725 -850);
FORCEPROP 2 LAST CDS_LIB pure_quanta
J 0
(4725 -850);
PAINT MONO (4725 -850);
DISPLAY INVISIBLE (4725 -850);
WIRE 17 -1 (1850 3925)(1850 3975);
WIRE 17 -1 (1850 3975)(1850 4025);
WIRE 17 -1 (1850 4025)(1850 4075);
WIRE 17 -1 (1850 4075)(1850 4125);
WIRE 17 -1 (1850 4125)(1850 4175);
WIRE 17 -1 (1850 4175)(1850 4225);
WIRE 17 -1 (1850 4225)(1850 4275);
WIRE 17 -1 (1850 4275)(1850 4325);
WIRE 17 -1 (1850 4325)(1850 4375);
WIRE 17 -1 (1850 4375)(1850 4425);
WIRE 17 -1 (1850 4425)(1850 4475);
WIRE 17 -1 (1850 4475)(1850 4525);
WIRE 17 -1 (1850 4525)(1850 4575);
WIRE 17 -1 (1850 4575)(1850 4625);
WIRE 17 -1 (1850 4625)(1850 4675);
WIRE 17 -1 (1850 4675)(2850 4675);
FORCEPROP 2 LAST SIG_NAME P5E_CPU1_PE4_TX_DP<15:0>
J 0
(1990 4685);
DISPLAY 0.680851 (1990 4685);
PAINT WHITE (1990 4685);
WIRE 17 -1 (1850 3075)(1850 3125);
WIRE 17 -1 (1850 3125)(1850 3175);
WIRE 17 -1 (1850 3175)(1850 3225);
WIRE 17 -1 (1850 3225)(1850 3275);
WIRE 17 -1 (1850 3275)(1850 3325);
WIRE 17 -1 (1850 3325)(1850 3375);
WIRE 17 -1 (1850 3375)(1850 3425);
WIRE 17 -1 (1850 3425)(1850 3475);
WIRE 17 -1 (1850 3475)(1850 3525);
WIRE 17 -1 (1850 3525)(1850 3575);
WIRE 17 -1 (1850 3575)(1850 3625);
WIRE 17 -1 (1850 3625)(1850 3675);
WIRE 17 -1 (1850 3675)(1850 3725);
WIRE 17 -1 (1850 3725)(1850 3775);
WIRE 17 -1 (1850 3775)(1850 3825);
WIRE 17 -1 (1850 3825)(2850 3825);
FORCEPROP 2 LAST SIG_NAME P5E_CPU1_PE4_TX_DN<15:0>
J 0
(1990 3835);
DISPLAY 0.680851 (1990 3835);
PAINT WHITE (1990 3835);
WIRE 17 -1 (-1600 3925)(-1600 3975);
WIRE 17 -1 (-1600 3975)(-1600 4025);
WIRE 17 -1 (-1600 4025)(-1600 4075);
WIRE 17 -1 (-1600 4075)(-1600 4125);
WIRE 17 -1 (-1600 4125)(-1600 4175);
WIRE 17 -1 (-1600 4175)(-1600 4225);
WIRE 17 -1 (-1600 4225)(-1600 4275);
WIRE 17 -1 (-1600 4275)(-1600 4325);
WIRE 17 -1 (-1600 4325)(-1600 4375);
WIRE 17 -1 (-1600 4375)(-1600 4425);
WIRE 17 -1 (-1600 4425)(-1600 4475);
WIRE 17 -1 (-1600 4475)(-1600 4525);
WIRE 17 -1 (-1600 4525)(-1600 4575);
WIRE 17 -1 (-1600 4575)(-1600 4625);
WIRE 17 -1 (-1600 4625)(-1600 4675);
WIRE 17 -1 (-2750 4675)(-1600 4675);
FORCEPROP 2 LAST SIG_NAME P5E_CPU1_PE4_RX_DP<15:0>
J 0
(-2635 4685);
DISPLAY 0.680851 (-2635 4685);
PAINT WHITE (-2635 4685);
WIRE 17 -1 (-1600 3075)(-1600 3125);
WIRE 17 -1 (-1600 3125)(-1600 3175);
WIRE 17 -1 (-1600 3175)(-1600 3225);
WIRE 17 -1 (-1600 3225)(-1600 3275);
WIRE 17 -1 (-1600 3275)(-1600 3325);
WIRE 17 -1 (-1600 3325)(-1600 3375);
WIRE 17 -1 (-1600 3375)(-1600 3425);
WIRE 17 -1 (-1600 3425)(-1600 3475);
WIRE 17 -1 (-1600 3475)(-1600 3525);
WIRE 17 -1 (-1600 3525)(-1600 3575);
WIRE 17 -1 (-1600 3575)(-1600 3625);
WIRE 17 -1 (-1600 3625)(-1600 3675);
WIRE 17 -1 (-1600 3675)(-1600 3725);
WIRE 17 -1 (-1600 3725)(-1600 3775);
WIRE 17 -1 (-1600 3775)(-1600 3825);
WIRE 17 -1 (-2750 3825)(-1600 3825);
FORCEPROP 2 LAST SIG_NAME P5E_CPU1_PE4_RX_DN<15:0>
J 0
(-2635 3835);
DISPLAY 0.680851 (-2635 3835);
PAINT WHITE (-2635 3835);
WIRE 16 -1 (-1500 3800)(-1075 3800);
WIRE 16 -1 (-1500 3750)(-1075 3750);
WIRE 16 -1 (-1500 3700)(-1075 3700);
WIRE 16 -1 (-1500 3650)(-1075 3650);
WIRE 16 -1 (-1500 3600)(-1075 3600);
WIRE 16 -1 (-1500 3550)(-1075 3550);
WIRE 16 -1 (-1500 3500)(-1075 3500);
WIRE 16 -1 (-1500 3450)(-1075 3450);
WIRE 16 -1 (-1500 3400)(-1075 3400);
WIRE 16 -1 (-1500 3350)(-1075 3350);
WIRE 16 -1 (-1500 3300)(-1075 3300);
WIRE 16 -1 (-1500 3250)(-1075 3250);
WIRE 16 -1 (-1500 3200)(-1075 3200);
WIRE 16 -1 (-1500 3150)(-1075 3150);
WIRE 16 -1 (-1500 3100)(-1075 3100);
WIRE 16 -1 (-1500 3050)(-1075 3050);
WIRE 16 -1 (-1500 4650)(-1075 4650);
WIRE 16 -1 (-1500 4600)(-1075 4600);
WIRE 16 -1 (-1500 4550)(-1075 4550);
WIRE 16 -1 (-1500 4500)(-1075 4500);
WIRE 16 -1 (-1500 4450)(-1075 4450);
WIRE 16 -1 (-1500 4400)(-1075 4400);
WIRE 16 -1 (-1500 4350)(-1075 4350);
WIRE 16 -1 (-1500 4300)(-1075 4300);
WIRE 16 -1 (-1500 4250)(-1075 4250);
WIRE 16 -1 (-1500 4200)(-1075 4200);
WIRE 16 -1 (-1500 4150)(-1075 4150);
WIRE 16 -1 (-1500 4100)(-1075 4100);
WIRE 16 -1 (-1500 4050)(-1075 4050);
WIRE 16 -1 (-1500 4000)(-1075 4000);
WIRE 16 -1 (-1500 3950)(-1075 3950);
WIRE 16 -1 (-1500 3900)(-1075 3900);
WIRE 16 -1 (1325 3800)(1750 3800);
WIRE 16 -1 (1325 3750)(1750 3750);
WIRE 16 -1 (1325 3700)(1750 3700);
WIRE 16 -1 (1325 3650)(1750 3650);
WIRE 16 -1 (1325 3600)(1750 3600);
WIRE 16 -1 (1325 3550)(1750 3550);
WIRE 16 -1 (1325 3500)(1750 3500);
WIRE 16 -1 (1325 3450)(1750 3450);
WIRE 16 -1 (1325 3400)(1750 3400);
WIRE 16 -1 (1325 3350)(1750 3350);
WIRE 16 -1 (1325 3300)(1750 3300);
WIRE 16 -1 (1325 3250)(1750 3250);
WIRE 16 -1 (1325 3200)(1750 3200);
WIRE 16 -1 (1325 3150)(1750 3150);
WIRE 16 -1 (1325 3100)(1750 3100);
WIRE 16 -1 (1325 3050)(1750 3050);
WIRE 16 -1 (1325 4650)(1750 4650);
WIRE 16 -1 (1325 4600)(1750 4600);
WIRE 16 -1 (1325 4550)(1750 4550);
WIRE 16 -1 (1325 4500)(1750 4500);
WIRE 16 -1 (1325 4450)(1750 4450);
WIRE 16 -1 (1325 4400)(1750 4400);
WIRE 16 -1 (1325 4350)(1750 4350);
WIRE 16 -1 (1325 4300)(1750 4300);
WIRE 16 -1 (1325 4250)(1750 4250);
WIRE 16 -1 (1325 4200)(1750 4200);
WIRE 16 -1 (1325 4150)(1750 4150);
WIRE 16 -1 (1325 4100)(1750 4100);
WIRE 16 -1 (1325 4050)(1750 4050);
WIRE 16 -1 (1325 4000)(1750 4000);
WIRE 16 -1 (1325 3950)(1750 3950);
WIRE 16 -1 (1325 3900)(1750 3900);
FORCENOTE
20210818 MODIFY FOR GT
(-1150 5400) 0;
DISPLAY LEFT (-1150 5400);
DISPLAY 2.510638 (-1150 5400);
PAINT PINK (-1150 5400);
QUIT
